G04 ================== begin FILE IDENTIFICATION RECORD ==================*
G04 Layout Name:  9048_F0T_Management_Board_D_brd_V04_1213_1625.brd*
G04 Film Name:    gnd*
G04 File Format:  Gerber RS274X*
G04 File Origin:  Cadence Allegro 17.2-S081*
G04 Origin Date:  Tue Dec 13 16:31:10 2022*
G04 *
G04 Layer:  DRAWING FORMAT/TITLE_BLOCK_A*
G04 Layer:  DRAWING FORMAT/TITLE_BLOCK*
G04 Layer:  VIA CLASS/GND*
G04 Layer:  PIN/GND*
G04 Layer:  MANUFACTURING/PHOTOPLOT_OUTLINE*
G04 Layer:  ETCH/GND*
G04 Layer:  DRAWING FORMAT/TITLE_DATA_GND*
G04 *
G04 Offset:    (0.00 0.00)*
G04 Mirror:    No*
G04 Mode:      Negative*
G04 Rotation:  0*
G04 FullContactRelief:  No*
G04 UndefLineWidth:     6.00*
G04 ================== end FILE IDENTIFICATION RECORD ====================*
%FSLAX25Y25*MOIN*%
%IR0*IPPOS*OFA0.00000B0.00000*MIA0B0*SFA1.00000B1.00000*%
%ADD19C,.03*%
%ADD25C,.052*%
%ADD23C,.061*%
%ADD39C,.071*%
%ADD28C,.026*%
%AMMACRO37*
4,1,36,.0025,0.0,
.002462,.000434,
.002349,.000855,
.002165,.00125,
.001915,.001607,
.001607,.001915,
.00125,.002165,
.000855,.002349,
.000434,.002462,
0.0,.0025,
-.000434,.002462,
-.000855,.002349,
-.00125,.002165,
-.001607,.001915,
-.001915,.001607,
-.002165,.00125,
-.002349,.000855,
-.002462,.000434,
-.0025,0.0,
-.002462,-.000434,
-.002349,-.000855,
-.002165,-.00125,
-.001915,-.001607,
-.001607,-.001915,
-.00125,-.002165,
-.000855,-.002349,
-.000434,-.002462,
0.0,-.0025,
.000434,-.002462,
.000855,-.002349,
.00125,-.002165,
.001607,-.001915,
.001915,-.001607,
.002165,-.00125,
.002349,-.000855,
.002462,-.000434,
.0025,0.0,
315.*
%
%ADD37MACRO37*%
%AMMACRO22*
4,1,36,.0025,0.0,
.002462,.000434,
.002349,.000855,
.002165,.00125,
.001915,.001607,
.001607,.001915,
.00125,.002165,
.000855,.002349,
.000434,.002462,
0.0,.0025,
-.000434,.002462,
-.000855,.002349,
-.00125,.002165,
-.001607,.001915,
-.001915,.001607,
-.002165,.00125,
-.002349,.000855,
-.002462,.000434,
-.0025,0.0,
-.002462,-.000434,
-.002349,-.000855,
-.002165,-.00125,
-.001915,-.001607,
-.001607,-.001915,
-.00125,-.002165,
-.000855,-.002349,
-.000434,-.002462,
0.0,-.0025,
.000434,-.002462,
.000855,-.002349,
.00125,-.002165,
.001607,-.001915,
.001915,-.001607,
.002165,-.00125,
.002349,-.000855,
.002462,-.000434,
.0025,0.0,
180.*
%
%ADD22MACRO22*%
%AMMACRO14*
4,1,36,.0025,0.0,
.002462,.000434,
.002349,.000855,
.002165,.00125,
.001915,.001607,
.001607,.001915,
.00125,.002165,
.000855,.002349,
.000434,.002462,
0.0,.0025,
-.000434,.002462,
-.000855,.002349,
-.00125,.002165,
-.001607,.001915,
-.001915,.001607,
-.002165,.00125,
-.002349,.000855,
-.002462,.000434,
-.0025,0.0,
-.002462,-.000434,
-.002349,-.000855,
-.002165,-.00125,
-.001915,-.001607,
-.001607,-.001915,
-.00125,-.002165,
-.000855,-.002349,
-.000434,-.002462,
0.0,-.0025,
.000434,-.002462,
.000855,-.002349,
.00125,-.002165,
.001607,-.001915,
.001915,-.001607,
.002165,-.00125,
.002349,-.000855,
.002462,-.000434,
.0025,0.0,
270.*
%
%ADD14MACRO14*%
%AMMACRO41*
4,1,36,.003,0.0,
.002954,.000521,
.002819,.001026,
.002598,.0015,
.002298,.001928,
.001928,.002298,
.0015,.002598,
.001026,.002819,
.000521,.002954,
0.0,.003,
-.000521,.002954,
-.001026,.002819,
-.0015,.002598,
-.001928,.002298,
-.002298,.001928,
-.002598,.0015,
-.002819,.001026,
-.002954,.000521,
-.003,0.0,
-.002954,-.000521,
-.002819,-.001026,
-.002598,-.0015,
-.002298,-.001928,
-.001928,-.002298,
-.0015,-.002598,
-.001026,-.002819,
-.000521,-.002954,
0.0,-.003,
.000521,-.002954,
.001026,-.002819,
.0015,-.002598,
.001928,-.002298,
.002298,-.001928,
.002598,-.0015,
.002819,-.001026,
.002954,-.000521,
.003,0.0,
270.*
%
%ADD41MACRO41*%
%AMMACRO44*
4,1,36,-.003,0.0,
-.002954,.000521,
-.002819,.001026,
-.002598,.0015,
-.002298,.001928,
-.001928,.002298,
-.0015,.002598,
-.001026,.002819,
-.000521,.002954,
0.0,.003,
.000521,.002954,
.001026,.002819,
.0015,.002598,
.001928,.002298,
.002298,.001928,
.002598,.0015,
.002819,.001026,
.002954,.000521,
.003,0.0,
.002954,-.000521,
.002819,-.001026,
.002598,-.0015,
.002298,-.001928,
.001928,-.002298,
.0015,-.002598,
.001026,-.002819,
.000521,-.002954,
0.0,-.003,
-.000521,-.002954,
-.001026,-.002819,
-.0015,-.002598,
-.001928,-.002298,
-.002298,-.001928,
-.002598,-.0015,
-.002819,-.001026,
-.002954,-.000521,
-.003,0.0,
270.*
%
%ADD44MACRO44*%
%ADD40C,.0435*%
%ADD32C,.048*%
%AMMACRO31*
4,1,16,.04562,.02794,
.049779,.019594,
.052425,.010652,
.053478,.001387,
.052906,-.007921,
.050727,-.016987,
.047007,-.025538,
.04562,-.02794,
.0507,-.03302,
.055664,-.023714,
.058936,-.013688,
.060417,-.003246,
.060063,.007295,
.057884,.017614,
.053946,.027397,
.0507,.03302,
.04562,.02794,
90.*
4,1,16,.02794,-.04562,
.019594,-.049779,
.010652,-.052425,
.001387,-.053478,
-.007921,-.052906,
-.016987,-.050727,
-.025538,-.047007,
-.02794,-.04562,
-.03302,-.0507,
-.023714,-.055664,
-.013688,-.058936,
-.003246,-.060417,
.007295,-.060063,
.017614,-.057884,
.027397,-.053946,
.03302,-.0507,
.02794,-.04562,
90.*
4,1,16,-.04562,-.02794,
-.049779,-.019594,
-.052425,-.010652,
-.053478,-.001387,
-.052906,.007921,
-.050727,.016987,
-.047007,.025538,
-.04562,.02794,
-.0507,.03302,
-.055664,.023714,
-.058936,.013688,
-.060417,.003246,
-.060063,-.007295,
-.057884,-.017614,
-.053946,-.027397,
-.0507,-.03302,
-.04562,-.02794,
90.*
4,1,16,-.02794,.04562,
-.019594,.049779,
-.010652,.052425,
-.001387,.053478,
.007921,.052906,
.016987,.050727,
.025538,.047007,
.02794,.04562,
.03302,.0507,
.023714,.055664,
.013688,.058936,
.003246,.060417,
-.007295,.060063,
-.017614,.057884,
-.027397,.053946,
-.03302,.0507,
-.02794,.04562,
90.*
%
%ADD31MACRO31*%
%ADD15C,.066*%
%AMMACRO18*
4,1,14,.06158,.03329,
.066425,.022091,
.069252,.010221,
.069975,-.00196,
.068571,-.014081,
.065084,-.025775,
.06158,-.03329,
.06672,-.03844,
.072381,-.02627,
.075844,-.013302,
.077001,.00007,
.075819,.01344,
.072334,.026402,
.06672,.03844,
.06158,.03329,
0.0*
4,1,14,.03329,-.06158,
.022091,-.066425,
.010221,-.069252,
-.00196,-.069975,
-.014081,-.068571,
-.025775,-.065084,
-.03329,-.06158,
-.03844,-.06672,
-.02627,-.072381,
-.013302,-.075844,
.00007,-.077001,
.01344,-.075819,
.026402,-.072334,
.03844,-.06672,
.03329,-.06158,
0.0*
4,1,14,-.06158,-.03329,
-.066425,-.022091,
-.069252,-.010221,
-.069975,.00196,
-.068571,.014081,
-.065084,.025775,
-.06158,.03329,
-.06672,.03844,
-.072381,.02627,
-.075844,.013302,
-.077001,-.00007,
-.075819,-.01344,
-.072334,-.026402,
-.06672,-.03844,
-.06158,-.03329,
0.0*
4,1,14,-.03329,.06158,
-.022091,.066425,
-.010221,.069252,
.00196,.069975,
.014081,.068571,
.025775,.065084,
.03329,.06158,
.03844,.06672,
.02627,.072381,
.013302,.075844,
-.00007,.077001,
-.01344,.075819,
-.026402,.072334,
-.03844,.06672,
-.03329,.06158,
0.0*
%
%ADD18MACRO18*%
%AMMACRO36*
4,1,15,.06525,.03697,
.070678,.025078,
.073959,.012424,
.074993,-.000608,
.073748,-.013621,
.070263,-.026221,
.06525,-.03697,
.07037,-.04209,
.07661,-.029231,
.080522,-.015484,
.081987,-.001266,
.080961,.01299,
.077476,.026852,
.071636,.039897,
.07037,.04209,
.06525,.03697,
0.0*
4,1,15,.03697,-.06525,
.025078,-.070678,
.012424,-.073959,
-.000608,-.074993,
-.013621,-.073748,
-.026221,-.070263,
-.03697,-.06525,
-.04209,-.07037,
-.029231,-.07661,
-.015484,-.080522,
-.001266,-.081987,
.01299,-.080961,
.026852,-.077476,
.039897,-.071636,
.04209,-.07037,
.03697,-.06525,
0.0*
4,1,15,-.06525,-.03697,
-.070678,-.025078,
-.073959,-.012424,
-.074993,.000608,
-.073748,.013621,
-.070263,.026221,
-.06525,.03697,
-.07037,.04209,
-.07661,.029231,
-.080522,.015484,
-.081987,.001266,
-.080961,-.01299,
-.077476,-.026852,
-.071636,-.039897,
-.07037,-.04209,
-.06525,-.03697,
0.0*
4,1,15,-.03697,.06525,
-.025078,.070678,
-.012424,.073959,
.000608,.074993,
.013621,.073748,
.026221,.070263,
.03697,.06525,
.04209,.07037,
.029231,.07661,
.015484,.080522,
.001266,.081987,
-.01299,.080961,
-.026852,.077476,
-.039897,.071636,
-.04209,.07037,
-.03697,.06525,
0.0*
%
%ADD36MACRO36*%
%ADD26C,.078*%
%ADD11C,.087*%
%ADD33C,.097*%
%AMMACRO17*
4,1,15,.06231,.03403,
.067273,.022693,
.070191,.010666,
.070977,-.001684,
.069606,-.013984,
.066121,-.025858,
.06231,-.03403,
.06745,-.03917,
.073227,-.026862,
.076779,-.013739,
.077998,-.000197,
.076848,.01335,
.073362,.026492,
.067647,.038828,
.06745,.03917,
.06231,.03403,
0.0*
4,1,15,.03403,-.06231,
.022693,-.067273,
.010666,-.070191,
-.001684,-.070977,
-.013984,-.069606,
-.025858,-.066121,
-.03403,-.06231,
-.03917,-.06745,
-.026862,-.073227,
-.013739,-.076779,
-.000197,-.077998,
.01335,-.076848,
.026492,-.073362,
.038828,-.067647,
.03917,-.06745,
.03403,-.06231,
0.0*
4,1,15,-.06231,-.03403,
-.067273,-.022693,
-.070191,-.010666,
-.070977,.001684,
-.069606,.013984,
-.066121,.025858,
-.06231,.03403,
-.06745,.03917,
-.073227,.026862,
-.076779,.013739,
-.077998,.000197,
-.076848,-.01335,
-.073362,-.026492,
-.067647,-.038828,
-.06745,-.03917,
-.06231,-.03403,
0.0*
4,1,15,-.03403,.06231,
-.022693,.067273,
-.010666,.070191,
.001684,.070977,
.013984,.069606,
.025858,.066121,
.03403,.06231,
.03917,.06745,
.026862,.073227,
.013739,.076779,
.000197,.077998,
-.01335,.076848,
-.026492,.073362,
-.038828,.067647,
-.03917,.06745,
-.03403,.06231,
0.0*
%
%ADD17MACRO17*%
%AMMACRO30*
4,1,16,.0711,.04282,
.077455,.029823,
.081457,.01592,
.082984,.001533,
.08199,-.0129,
.078504,-.026942,
.072633,-.040164,
.0711,-.04282,
.07619,-.04791,
.083352,-.033952,
.087981,-.018962,
.089937,-.003396,
.089161,.012273,
.085675,.027569,
.079586,.042027,
.07619,.04791,
.0711,.04282,
0.0*
4,1,16,.04282,-.0711,
.029823,-.077455,
.01592,-.081457,
.001533,-.082984,
-.0129,-.08199,
-.026942,-.078504,
-.040164,-.072633,
-.04282,-.0711,
-.04791,-.07619,
-.033952,-.083352,
-.018962,-.087981,
-.003396,-.089937,
.012273,-.089161,
.027569,-.085675,
.042027,-.079586,
.04791,-.07619,
.04282,-.0711,
0.0*
4,1,16,-.0711,-.04282,
-.077455,-.029823,
-.081457,-.01592,
-.082984,-.001533,
-.08199,.0129,
-.078504,.026942,
-.072633,.040164,
-.0711,.04282,
-.07619,.04791,
-.083352,.033952,
-.087981,.018962,
-.089937,.003396,
-.089161,-.012273,
-.085675,-.027569,
-.079586,-.042027,
-.07619,-.04791,
-.0711,-.04282,
0.0*
4,1,16,-.04282,.0711,
-.029823,.077455,
-.01592,.081457,
-.001533,.082984,
.0129,.08199,
.026942,.078504,
.040164,.072633,
.04282,.0711,
.04791,.07619,
.033952,.083352,
.018962,.087981,
.003396,.089937,
-.012273,.089161,
-.027569,.085675,
-.042027,.079586,
-.04791,.07619,
-.04282,.0711,
0.0*
%
%ADD30MACRO30*%
%AMMACRO35*
4,1,15,.02142,.01082,
.022973,.006936,
.023829,.002841,
.02396,-.00134,
.023364,-.00548,
.022057,-.009454,
.02142,-.01082,
.02657,-.01597,
.02894,-.011114,
.03043,-.005919,
.030995,-.000545,
.030619,.004845,
.029313,.010088,
.027115,.015025,
.02657,.01597,
.02142,.01082,
0.0*
4,1,15,.01082,-.02142,
.006936,-.022973,
.002841,-.023829,
-.00134,-.02396,
-.00548,-.023364,
-.009454,-.022057,
-.01082,-.02142,
-.01597,-.02657,
-.011114,-.02894,
-.005919,-.03043,
-.000545,-.030995,
.004845,-.030619,
.010088,-.029313,
.015025,-.027115,
.01597,-.02657,
.01082,-.02142,
0.0*
4,1,15,-.02142,-.01082,
-.022973,-.006936,
-.023829,-.002841,
-.02396,.00134,
-.023364,.00548,
-.022057,.009454,
-.02142,.01082,
-.02657,.01597,
-.02894,.011114,
-.03043,.005919,
-.030995,.000545,
-.030619,-.004845,
-.029313,-.010088,
-.027115,-.015025,
-.02657,-.01597,
-.02142,-.01082,
0.0*
4,1,15,-.01082,.02142,
-.006936,.022973,
-.002841,.023829,
.00134,.02396,
.00548,.023364,
.009454,.022057,
.01082,.02142,
.01597,.02657,
.011114,.02894,
.005919,.03043,
.000545,.030995,
-.004845,.030619,
-.010088,.029313,
-.015025,.027115,
-.01597,.02657,
-.01082,.02142,
0.0*
%
%ADD35MACRO35*%
%AMMACRO34*
4,1,15,.01993,.00932,
.021246,.005718,
.021916,.001941,
.02192,-.001894,
.021258,-.005671,
.01995,-.009276,
.01993,-.00932,
.02511,-.01451,
.027248,-.009929,
.028558,-.005047,
.029001,-.000011,
.028562,.005025,
.027256,.009909,
.025121,.014491,
.02511,.01451,
.01993,.00932,
90.*
4,1,15,.00932,-.01993,
.005718,-.021246,
.001941,-.021916,
-.001894,-.02192,
-.005671,-.021258,
-.009276,-.01995,
-.00932,-.01993,
-.01451,-.02511,
-.009929,-.027248,
-.005047,-.028558,
-.000011,-.029001,
.005025,-.028562,
.009909,-.027256,
.014491,-.025121,
.01451,-.02511,
.00932,-.01993,
90.*
4,1,15,-.01993,-.00932,
-.021246,-.005718,
-.021916,-.001941,
-.02192,.001894,
-.021258,.005671,
-.01995,.009276,
-.01993,.00932,
-.02511,.01451,
-.027248,.009929,
-.028558,.005047,
-.029001,.000011,
-.028562,-.005025,
-.027256,-.009909,
-.025121,-.014491,
-.02511,-.01451,
-.01993,-.00932,
90.*
4,1,15,-.00932,.01993,
-.005718,.021246,
-.001941,.021916,
.001894,.02192,
.005671,.021258,
.009276,.01995,
.00932,.01993,
.01451,.02511,
.009929,.027248,
.005047,.028558,
.000011,.029001,
-.005025,.028562,
-.009909,.027256,
-.014491,.025121,
-.01451,.02511,
-.00932,.01993,
90.*
%
%ADD34MACRO34*%
%AMMACRO24*
4,1,15,.02475,.01414,
.026829,.009627,
.028094,.004822,
.028504,-.000129,
.028049,-.005077,
.026741,-.009871,
.02475,-.01414,
.02984,-.01923,
.032726,-.013756,
.034617,-.007864,
.035457,-.001734,
.03522,.00445,
.033912,.010498,
.031574,.016227,
.02984,.01923,
.02475,.01414,
0.0*
4,1,15,.01414,-.02475,
.009627,-.026829,
.004822,-.028094,
-.000129,-.028504,
-.005077,-.028049,
-.009871,-.026741,
-.01414,-.02475,
-.01923,-.02984,
-.013756,-.032726,
-.007864,-.034617,
-.001734,-.035457,
.00445,-.03522,
.010498,-.033912,
.016227,-.031574,
.01923,-.02984,
.01414,-.02475,
0.0*
4,1,15,-.02475,-.01414,
-.026829,-.009627,
-.028094,-.004822,
-.028504,.000129,
-.028049,.005077,
-.026741,.009871,
-.02475,.01414,
-.02984,.01923,
-.032726,.013756,
-.034617,.007864,
-.035457,.001734,
-.03522,-.00445,
-.033912,-.010498,
-.031574,-.016227,
-.02984,-.01923,
-.02475,-.01414,
0.0*
4,1,15,-.01414,.02475,
-.009627,.026829,
-.004822,.028094,
.000129,.028504,
.005077,.028049,
.009871,.026741,
.01414,.02475,
.01923,.02984,
.013756,.032726,
.007864,.034617,
.001734,.035457,
-.00445,.03522,
-.010498,.033912,
-.016227,.031574,
-.01923,.02984,
-.01414,.02475,
0.0*
%
%ADD24MACRO24*%
%AMMACRO10*
4,1,15,.03682,.01914,
.039584,.012455,
.041146,.005393,
.041457,-.001834,
.040509,-.009005,
.03833,-.015903,
.03682,-.01914,
.04197,-.0243,
.045552,-.016643,
.04775,-.00848,
.048497,-.000059,
.047771,.008363,
.045593,.016531,
.042029,.024197,
.04197,.0243,
.03682,.01914,
0.0*
4,1,15,.01914,-.03682,
.012455,-.039584,
.005393,-.041146,
-.001834,-.041457,
-.009005,-.040509,
-.015903,-.03833,
-.01914,-.03682,
-.0243,-.04197,
-.016643,-.045552,
-.00848,-.04775,
-.000059,-.048497,
.008363,-.047771,
.016531,-.045593,
.024197,-.042029,
.0243,-.04197,
.01914,-.03682,
0.0*
4,1,15,-.03682,-.01914,
-.039584,-.012455,
-.041146,-.005393,
-.041457,.001834,
-.040509,.009005,
-.03833,.015903,
-.03682,.01914,
-.04197,.0243,
-.045552,.016643,
-.04775,.00848,
-.048497,.000059,
-.047771,-.008363,
-.045593,-.016531,
-.042029,-.024197,
-.04197,-.0243,
-.03682,-.01914,
0.0*
4,1,15,-.01914,.03682,
-.012455,.039584,
-.005393,.041146,
.001834,.041457,
.009005,.040509,
.015903,.03833,
.01914,.03682,
.0243,.04197,
.016643,.045552,
.00848,.04775,
.000059,.048497,
-.008363,.047771,
-.016531,.045593,
-.024197,.042029,
-.0243,.04197,
-.01914,.03682,
0.0*
%
%ADD10MACRO10*%
%ADD29O,.156X.219*%
%ADD21C,.155*%
%AMMACRO38*
4,1,36,.0025,0.0,
.002462,.000434,
.002349,.000855,
.002165,.00125,
.001915,.001607,
.001607,.001915,
.00125,.002165,
.000855,.002349,
.000434,.002462,
0.0,.0025,
-.000434,.002462,
-.000855,.002349,
-.00125,.002165,
-.001607,.001915,
-.001915,.001607,
-.002165,.00125,
-.002349,.000855,
-.002462,.000434,
-.0025,0.0,
-.002462,-.000434,
-.002349,-.000855,
-.002165,-.00125,
-.001915,-.001607,
-.001607,-.001915,
-.00125,-.002165,
-.000855,-.002349,
-.000434,-.002462,
0.0,-.0025,
.000434,-.002462,
.000855,-.002349,
.00125,-.002165,
.001607,-.001915,
.001915,-.001607,
.002165,-.00125,
.002349,-.000855,
.002462,-.000434,
.0025,0.0,
45.*
%
%ADD38MACRO38*%
%AMMACRO20*
4,1,36,.0025,0.0,
.002462,.000434,
.002349,.000855,
.002165,.00125,
.001915,.001607,
.001607,.001915,
.00125,.002165,
.000855,.002349,
.000434,.002462,
0.0,.0025,
-.000434,.002462,
-.000855,.002349,
-.00125,.002165,
-.001607,.001915,
-.001915,.001607,
-.002165,.00125,
-.002349,.000855,
-.002462,.000434,
-.0025,0.0,
-.002462,-.000434,
-.002349,-.000855,
-.002165,-.00125,
-.001915,-.001607,
-.001607,-.001915,
-.00125,-.002165,
-.000855,-.002349,
-.000434,-.002462,
0.0,-.0025,
.000434,-.002462,
.000855,-.002349,
.00125,-.002165,
.001607,-.001915,
.001915,-.001607,
.002165,-.00125,
.002349,-.000855,
.002462,-.000434,
.0025,0.0,
90.*
%
%ADD20MACRO20*%
%AMMACRO42*
4,1,36,.003,0.0,
.002954,.000521,
.002819,.001026,
.002598,.0015,
.002298,.001928,
.001928,.002298,
.0015,.002598,
.001026,.002819,
.000521,.002954,
0.0,.003,
-.000521,.002954,
-.001026,.002819,
-.0015,.002598,
-.001928,.002298,
-.002298,.001928,
-.002598,.0015,
-.002819,.001026,
-.002954,.000521,
-.003,0.0,
-.002954,-.000521,
-.002819,-.001026,
-.002598,-.0015,
-.002298,-.001928,
-.001928,-.002298,
-.0015,-.002598,
-.001026,-.002819,
-.000521,-.002954,
0.0,-.003,
.000521,-.002954,
.001026,-.002819,
.0015,-.002598,
.001928,-.002298,
.002298,-.001928,
.002598,-.0015,
.002819,-.001026,
.002954,-.000521,
.003,0.0,
90.*
%
%ADD42MACRO42*%
%AMMACRO16*
4,1,36,.0025,0.0,
.002462,.000434,
.002349,.000855,
.002165,.00125,
.001915,.001607,
.001607,.001915,
.00125,.002165,
.000855,.002349,
.000434,.002462,
0.0,.0025,
-.000434,.002462,
-.000855,.002349,
-.00125,.002165,
-.001607,.001915,
-.001915,.001607,
-.002165,.00125,
-.002349,.000855,
-.002462,.000434,
-.0025,0.0,
-.002462,-.000434,
-.002349,-.000855,
-.002165,-.00125,
-.001915,-.001607,
-.001607,-.001915,
-.00125,-.002165,
-.000855,-.002349,
-.000434,-.002462,
0.0,-.0025,
.000434,-.002462,
.000855,-.002349,
.00125,-.002165,
.001607,-.001915,
.001915,-.001607,
.002165,-.00125,
.002349,-.000855,
.002462,-.000434,
.0025,0.0,
0.0*
%
%ADD16MACRO16*%
%AMMACRO43*
4,1,36,-.003,0.0,
-.002954,.000521,
-.002819,.001026,
-.002598,.0015,
-.002298,.001928,
-.001928,.002298,
-.0015,.002598,
-.001026,.002819,
-.000521,.002954,
0.0,.003,
.000521,.002954,
.001026,.002819,
.0015,.002598,
.001928,.002298,
.002298,.001928,
.002598,.0015,
.002819,.001026,
.002954,.000521,
.003,0.0,
.002954,-.000521,
.002819,-.001026,
.002598,-.0015,
.002298,-.001928,
.001928,-.002298,
.0015,-.002598,
.001026,-.002819,
.000521,-.002954,
0.0,-.003,
-.000521,-.002954,
-.001026,-.002819,
-.0015,-.002598,
-.001928,-.002298,
-.002298,-.001928,
-.002598,-.0015,
-.002819,-.001026,
-.002954,-.000521,
-.003,0.0,
90.*
%
%ADD43MACRO43*%
%AMMACRO27*
4,1,36,.0025,0.0,
.002462,.000434,
.002349,.000855,
.002165,.00125,
.001915,.001607,
.001607,.001915,
.00125,.002165,
.000855,.002349,
.000434,.002462,
0.0,.0025,
-.000434,.002462,
-.000855,.002349,
-.00125,.002165,
-.001607,.001915,
-.001915,.001607,
-.002165,.00125,
-.002349,.000855,
-.002462,.000434,
-.0025,0.0,
-.002462,-.000434,
-.002349,-.000855,
-.002165,-.00125,
-.001915,-.001607,
-.001607,-.001915,
-.00125,-.002165,
-.000855,-.002349,
-.000434,-.002462,
0.0,-.0025,
.000434,-.002462,
.000855,-.002349,
.00125,-.002165,
.001607,-.001915,
.001915,-.001607,
.002165,-.00125,
.002349,-.000855,
.002462,-.000434,
.0025,0.0,
84.*
%
%ADD27MACRO27*%
%AMMACRO13*
4,1,15,.03682,.01914,
.039584,.012455,
.041146,.005393,
.041457,-.001834,
.040509,-.009005,
.03833,-.015903,
.03682,-.01914,
.04197,-.0243,
.045552,-.016643,
.04775,-.00848,
.048497,-.000059,
.047771,.008363,
.045593,.016531,
.042029,.024197,
.04197,.0243,
.03682,.01914,
180.*
4,1,15,.01914,-.03682,
.012455,-.039584,
.005393,-.041146,
-.001834,-.041457,
-.009005,-.040509,
-.015903,-.03833,
-.01914,-.03682,
-.0243,-.04197,
-.016643,-.045552,
-.00848,-.04775,
-.000059,-.048497,
.008363,-.047771,
.016531,-.045593,
.024197,-.042029,
.0243,-.04197,
.01914,-.03682,
180.*
4,1,15,-.03682,-.01914,
-.039584,-.012455,
-.041146,-.005393,
-.041457,.001834,
-.040509,.009005,
-.03833,.015903,
-.03682,.01914,
-.04197,.0243,
-.045552,.016643,
-.04775,.00848,
-.048497,.000059,
-.047771,-.008363,
-.045593,-.016531,
-.042029,-.024197,
-.04197,-.0243,
-.03682,-.01914,
180.*
4,1,15,-.01914,.03682,
-.012455,.039584,
-.005393,.041146,
.001834,.041457,
.009005,.040509,
.015903,.03833,
.01914,.03682,
.0243,.04197,
.016643,.045552,
.00848,.04775,
.000059,.048497,
-.008363,.047771,
-.016531,.045593,
-.024197,.042029,
-.0243,.04197,
-.01914,.03682,
180.*
%
%ADD13MACRO13*%
%AMMACRO12*
4,1,15,-.03682,.01914,
-.039584,.012455,
-.041146,.005393,
-.041457,-.001834,
-.040509,-.009005,
-.03833,-.015903,
-.03682,-.01914,
-.04197,-.0243,
-.045552,-.016643,
-.04775,-.00848,
-.048497,-.000059,
-.047771,.008363,
-.045593,.016531,
-.042029,.024197,
-.04197,.0243,
-.03682,.01914,
180.*
4,1,15,-.01914,-.03682,
-.012455,-.039584,
-.005393,-.041146,
.001834,-.041457,
.009005,-.040509,
.015903,-.03833,
.01914,-.03682,
.0243,-.04197,
.016643,-.045552,
.00848,-.04775,
.000059,-.048497,
-.008363,-.047771,
-.016531,-.045593,
-.024197,-.042029,
-.0243,-.04197,
-.01914,-.03682,
180.*
4,1,15,.03682,-.01914,
.039584,-.012455,
.041146,-.005393,
.041457,.001834,
.040509,.009005,
.03833,.015903,
.03682,.01914,
.04197,.0243,
.045552,.016643,
.04775,.00848,
.048497,.000059,
.047771,-.008363,
.045593,-.016531,
.042029,-.024197,
.04197,-.0243,
.03682,-.01914,
180.*
4,1,15,.01914,.03682,
.012455,.039584,
.005393,.041146,
-.001834,.041457,
-.009005,.040509,
-.015903,.03833,
-.01914,.03682,
-.0243,.04197,
-.016643,.045552,
-.00848,.04775,
-.000059,.048497,
.008363,.047771,
.016531,.045593,
.024197,.042029,
.0243,.04197,
.01914,.03682,
180.*
%
%ADD12MACRO12*%
%ADD45C,.006*%
%ADD57C,.07306*%
%ADD53C,.08008*%
%ADD47C,.06807*%
%ADD51C,.06809*%
%ADD52C,.09908*%
%ADD50R,.01002X.02504*%
%ADD49R,.01004X.02504*%
%ADD54O,.03004X.06504*%
%ADD48R,.02402X.02802*%
%ADD55O,.03006X.06506*%
%ADD46C,.16506*%
%ADD58R,.04924X.03014*%
%ADD56O,.2363X.2993*%
G75*
%LPD*%
G75*
G36*
G01X-407000Y-793716D02*
X2010999D01*
Y1475775D01*
X-407000D01*
Y-793716D01*
G37*
%LPC*%
G75*
G36*
G01X-15748Y472016D02*
G02X-9874Y466142I0J-5874D01*
G01Y25945D01*
G02X-15748Y20071I-5874J0D01*
G01X-70000D01*
G02X-75874Y25945I0J5874D01*
G01Y466142D01*
G02X-70000Y472016I5874J0D01*
G01X-15748D01*
G37*
G36*
G01X2004Y242282D02*
X2000Y242286D01*
Y247986D01*
X2004Y247990D01*
Y318862D01*
X8858D01*
G03X12831Y322835I0J3973D01*
G01Y332677D01*
G03X8858Y336650I-3973J0D01*
G01X2004D01*
Y442126D01*
G02X7874Y447996I5870J0D01*
G01X17717D01*
G03X21689Y451968I-1J3973D01*
G01Y467369D01*
X22132Y467812D01*
X23372D01*
X23781Y467404D01*
X38207D01*
X38828Y468024D01*
X40009D01*
X40378Y467655D01*
Y451968D01*
G03X44350Y447996I3973J1D01*
G01X50256D01*
G03X54228Y451968I-1J3973D01*
G01Y462100D01*
X122504D01*
Y451870D01*
G03X137339I7418J0D01*
G01Y462100D01*
X172543D01*
Y450098D01*
G03X183835I5646J0D01*
G01Y462100D01*
X252071D01*
Y450886D01*
G03X264937I6433J0D01*
G01Y462100D01*
X300122D01*
Y451968D01*
G03X304094Y447996I3973J1D01*
G01X310000D01*
G03X313973Y451969I0J3973D01*
G01Y467400D01*
X314385Y467812D01*
X315625D01*
X316034Y467404D01*
X330460D01*
X331081Y468024D01*
X332262D01*
X332642Y467644D01*
Y451968D01*
G03X336614Y447996I3973J1D01*
G01X346457D01*
G02X352327Y442126I0J-5870D01*
G01Y336650D01*
X345472D01*
G03X341500Y332678I0J-3973D01*
G01Y322834D01*
G03X345472Y318862I3972J0D01*
G01X352327D01*
Y271930D01*
X352331Y271926D01*
Y266763D01*
X352327Y266759D01*
Y7874D01*
G02X346457Y2004I-5870J0D01*
G01X7874D01*
G02X2004Y7874I0J5870D01*
G01Y242282D01*
G37*
G36*
G01X370079Y-515716D02*
G02X364205Y-509842I0J5874D01*
G01Y466142D01*
G02X370079Y472016I5874J0D01*
G01X476378D01*
G02X482252Y466142I0J-5874D01*
G01Y-509842D01*
G02X476378Y-515716I-5874J0D01*
G01X370079D01*
G37*
%LPD*%
G75*
G36*
G01X174084Y89317D02*
Y88762D01*
X173848D01*
Y87720D01*
X172346D01*
Y88762D01*
X172110D01*
Y88788D01*
X172056D01*
Y92392D01*
X173460D01*
Y89708D01*
X173689D01*
G02X174084Y89317I4J-391D01*
G37*
G36*
G01X168710Y89708D02*
Y92392D01*
X170114D01*
Y88788D01*
X170084D01*
Y88762D01*
X169848D01*
Y87720D01*
X168346D01*
Y88762D01*
X168110D01*
Y89317D01*
G02X168505Y89708I391J0D01*
G01X168710D01*
G37*
G36*
G01X164660Y89317D02*
Y88762D01*
X164424D01*
Y87720D01*
X162922D01*
Y88762D01*
X162686D01*
Y88788D01*
X162632D01*
Y92392D01*
X164036D01*
Y89708D01*
X164265D01*
G02X164660Y89317I4J-391D01*
G37*
G36*
G01X159286Y89708D02*
Y92392D01*
X160690D01*
Y88788D01*
X160660D01*
Y88762D01*
X160424D01*
Y87720D01*
X158922D01*
Y88762D01*
X158686D01*
Y89317D01*
G02X159081Y89708I391J0D01*
G01X159286D01*
G37*
G36*
G01X173689Y84752D02*
X173460D01*
Y82096D01*
X172056D01*
Y85700D01*
X172346D01*
Y86740D01*
X173848D01*
Y85698D01*
X174084D01*
Y85143D01*
G02X173689Y84752I-391J0D01*
G37*
G36*
G01X168110Y85143D02*
Y85698D01*
X168346D01*
Y86740D01*
X169848D01*
Y85700D01*
X170114D01*
Y82096D01*
X168710D01*
Y84752D01*
X168505D01*
G02X168110Y85143I-4J391D01*
G37*
G36*
G01X164265Y84752D02*
X164036D01*
Y82096D01*
X162632D01*
Y85700D01*
X162922D01*
Y86740D01*
X164424D01*
Y85698D01*
X164660D01*
Y85143D01*
G02X164265Y84752I-391J0D01*
G37*
G36*
G01X158686Y85143D02*
Y85698D01*
X158922D01*
Y86740D01*
X160424D01*
Y85700D01*
X160690D01*
Y82096D01*
X159286D01*
Y84752D01*
X159081D01*
G02X158686Y85143I-4J391D01*
G37*
G36*
G01X95870Y446986D02*
X99370D01*
G02Y443980I0J-1503D01*
G01X95870D01*
G02Y446986I0J1503D01*
G37*
G36*
G01X267080Y213090D02*
X263580D01*
G02Y216096I0J1503D01*
G01X267080D01*
G02Y213090I0J-1503D01*
G37*
G36*
G01X266080Y205760D02*
X262580D01*
G02Y208764I0J1502D01*
G01X266080D01*
G02Y205760I0J-1502D01*
G37*
G36*
G01X246488Y107294D02*
X249988D01*
G02Y104290I0J-1502D01*
G01X246488D01*
G02Y107294I0J1502D01*
G37*
G36*
G01X255213Y107602D02*
X258713D01*
G02Y104596I0J-1503D01*
G01X255213D01*
G02Y107602I0J1503D01*
G37*
G36*
G01X52750Y425702D02*
X56250D01*
G02Y422698I0J-1502D01*
G01X52750D01*
G02Y425702I0J1502D01*
G37*
G36*
G01X81990Y449588D02*
X85490D01*
G02Y446582I0J-1503D01*
G01X81990D01*
G02Y449588I0J1503D01*
G37*
G36*
G01X267722Y175288D02*
X264222D01*
G02Y178294I0J1503D01*
G01X267722D01*
G02Y175288I0J-1503D01*
G37*
G36*
G01X221225Y408648D02*
X217725D01*
G02Y411652I0J1502D01*
G01X221225D01*
G02Y408648I0J-1502D01*
G37*
G36*
G01X169347Y97784D02*
X172847D01*
G02Y94778I0J-1503D01*
G01X169347D01*
G02Y97784I0J1503D01*
G37*
G36*
G01X159923D02*
X163423D01*
G02Y94778I0J-1503D01*
G01X159923D01*
G02Y97784I0J1503D01*
G37*
G36*
G01X216725Y440718D02*
X213225D01*
G02Y443722I0J1502D01*
G01X216725D01*
G02Y440718I0J-1502D01*
G37*
G36*
G01X182350Y384132D02*
X178850D01*
G02Y387136I0J1502D01*
G01X182350D01*
G02Y384132I0J-1502D01*
G37*
G36*
G01X60622Y432776D02*
X64122D01*
G02Y429770I0J-1503D01*
G01X60622D01*
G02Y432776I0J1503D01*
G37*
G36*
G01X251198Y139374D02*
Y138820D01*
X250962D01*
Y137776D01*
X249462D01*
Y138820D01*
X249226D01*
Y139374D01*
G02X249620Y139765I391J0D01*
G01X249621Y139764D01*
X250803D01*
X250804Y139765D01*
G02X251198Y139374I3J-391D01*
G37*
G36*
G01X92801Y454296D02*
X96301D01*
G02Y451290I0J-1503D01*
G01X92801D01*
G02Y454296I0J1503D01*
G37*
G36*
G01X72150Y425702D02*
X75650D01*
G02Y422696I0J-1503D01*
G01X72150D01*
G02Y425702I0J1503D01*
G37*
G36*
G01X162550Y385832D02*
X159050D01*
G02Y388836I0J1502D01*
G01X162550D01*
G02Y385832I0J-1502D01*
G37*
G36*
G01X247192Y139374D02*
Y138820D01*
X246956D01*
Y137776D01*
X245454D01*
Y138820D01*
X245218D01*
Y139374D01*
G02X245613Y139765I391J0D01*
G01X245614Y139764D01*
X246796D01*
X246797Y139765D01*
G02X247192Y139374I4J-391D01*
G37*
G36*
G01X250749Y230304D02*
X253898D01*
G02Y227700I0J-1302D01*
G01X250749D01*
G02Y230304I0J1302D01*
G37*
G36*
G01X244450Y233454D02*
X247599D01*
G02Y230848I0J-1303D01*
G01X244450D01*
G02Y233454I0J1303D01*
G37*
G36*
G01X176859Y61386D02*
X184733D01*
G02Y55780I0J-2803D01*
G01X176859D01*
G02Y61386I0J2803D01*
G37*
G36*
G01X165048Y55480D02*
X172922D01*
G02Y49874I0J-2803D01*
G01X165048D01*
G02Y55480I0J2803D01*
G37*
G36*
G01X153237Y61386D02*
X161111D01*
G02Y55780I0J-2803D01*
G01X153237D01*
G02Y61386I0J2803D01*
G37*
G36*
G01X246797Y134809D02*
X246796Y134810D01*
X245614D01*
X245613Y134809D01*
G02X245218Y135200I-4J391D01*
G01Y135754D01*
X245454D01*
Y136798D01*
X246956D01*
Y135754D01*
X247192D01*
Y135200D01*
G02X246797Y134809I-391J0D01*
G37*
G36*
G01X250804D02*
X250803Y134810D01*
X249621D01*
X249620Y134809D01*
G02X249226Y135200I-3J391D01*
G01Y135754D01*
X249462D01*
Y136798D01*
X250962D01*
Y135754D01*
X251198D01*
Y135200D01*
G02X250804Y134809I-391J0D01*
G37*
G36*
G01X262978Y110892D02*
Y109708D01*
G02X262587Y109314I-391J-3D01*
G01X262032D01*
Y109550D01*
X260990D01*
Y111050D01*
X262032D01*
Y111286D01*
X262587D01*
G02X262978Y110892I0J-391D01*
G37*
G36*
G01X256078D02*
Y109708D01*
G02X255687Y109314I-391J-3D01*
G01X255132D01*
Y109550D01*
X254090D01*
Y111050D01*
X255132D01*
Y111286D01*
X255687D01*
G02X256078Y110892I0J-391D01*
G37*
G36*
G01X258022Y109708D02*
Y110892D01*
G02X258413Y111286I391J3D01*
G01X258968D01*
Y111050D01*
X260010D01*
Y109550D01*
X258968D01*
Y109314D01*
X258413D01*
G02X258022Y109708I0J391D01*
G37*
G36*
G01X251122D02*
Y110892D01*
G02X251513Y111286I391J3D01*
G01X252068D01*
Y111050D01*
X253110D01*
Y109550D01*
X252068D01*
Y109314D01*
X251513D01*
G02X251122Y109708I0J391D01*
G37*
G36*
G01X55908Y432978D02*
X57092D01*
G02X57486Y432587I3J-391D01*
G01Y432032D01*
X57250D01*
Y430990D01*
X55750D01*
Y432032D01*
X55514D01*
Y432587D01*
G02X55908Y432978I391J0D01*
G37*
G36*
G01X51908D02*
X53092D01*
G02X53486Y432587I3J-391D01*
G01Y432032D01*
X53250D01*
Y430990D01*
X51750D01*
Y432032D01*
X51514D01*
Y432587D01*
G02X51908Y432978I391J0D01*
G37*
G36*
G01X55514Y428413D02*
Y428968D01*
X55750D01*
Y430010D01*
X57250D01*
Y428968D01*
X57486D01*
Y428413D01*
G02X57092Y428022I-391J0D01*
G01X55908D01*
G02X55514Y428413I-3J391D01*
G37*
G36*
G01X51514D02*
Y428968D01*
X51750D01*
Y430010D01*
X53250D01*
Y428968D01*
X53486D01*
Y428413D01*
G02X53092Y428022I-391J0D01*
G01X51908D01*
G02X51514Y428413I-3J391D01*
G37*
G36*
G01X253898Y233454D02*
X257047D01*
G02Y230848I0J-1303D01*
G01X253898D01*
G02Y233454I0J1303D01*
G37*
G36*
G01X250749Y236604D02*
X253898D01*
G02Y233998I0J-1303D01*
G01X250749D01*
G02Y236604I0J1303D01*
G37*
G36*
G01X254924Y113180D02*
X253740D01*
G02X253346Y113571I-3J391D01*
G01Y114126D01*
X253582D01*
Y115168D01*
X255082D01*
Y114126D01*
X255318D01*
Y113571D01*
G02X254924Y113180I-391J0D01*
G37*
G36*
G01X258931D02*
X257747D01*
G02X257352Y113571I-4J391D01*
G01Y114126D01*
X257588D01*
Y115168D01*
X259090D01*
Y114126D01*
X259326D01*
Y113571D01*
G02X258931Y113180I-391J0D01*
G37*
G36*
G01X257747Y118136D02*
X258931D01*
G02X259326Y117745I4J-391D01*
G01Y117190D01*
X259090D01*
Y116148D01*
X257588D01*
Y117190D01*
X257352D01*
Y117745D01*
G02X257747Y118136I391J0D01*
G37*
G36*
G01X253740D02*
X254924D01*
G02X255318Y117745I3J-391D01*
G01Y117190D01*
X255082D01*
Y116148D01*
X253582D01*
Y117190D01*
X253346D01*
Y117745D01*
G02X253740Y118136I391J0D01*
G37*
G36*
G01X239998Y225853D02*
Y229002D01*
G02X242602I1302J0D01*
G01Y226194D01*
G02X242638Y225890I-1264J-304D01*
G02X242261Y224974I-1301J0D01*
G02X241300Y224551I-961J880D01*
G02X239998Y225853I0J1302D01*
G37*
G36*
G01X242870Y239000D02*
G02X243872Y238580I0J-1405D01*
G02Y236612I-853J-984D01*
G02X242870Y236192I-1002J985D01*
G02X242378Y236281I0J1404D01*
G01X242344Y236294D01*
X240395D01*
G02X239870Y236192I-525J1302D01*
G02Y239000I0J1404D01*
G02X240395Y238898I0J-1404D01*
G01X242344D01*
X242378Y238911D01*
G02X242870Y239000I492J-1315D01*
G37*
G36*
G01X116462Y64004D02*
Y62600D01*
X114161D01*
G03X113770Y62285I0J-400D01*
G02X113388Y61976I-383J82D01*
G01X112834D01*
Y62212D01*
X111790D01*
Y63714D01*
X112834D01*
Y63950D01*
X112858Y63974D01*
X112860Y63977D01*
Y64004D01*
X116462D01*
G37*
G36*
G01X109214Y67950D02*
X109768D01*
Y67714D01*
X110812D01*
Y66212D01*
X109770D01*
Y65946D01*
X106168D01*
Y67350D01*
X108823D01*
Y67553D01*
G02X109214Y67950I391J6D01*
G37*
G36*
G01X113779Y67350D02*
X116462D01*
Y65946D01*
X112860D01*
Y65976D01*
X112834D01*
Y66212D01*
X111790D01*
Y67714D01*
X112834D01*
Y67950D01*
X113388D01*
G02X113779Y67553I0J-391D01*
G01Y67350D01*
G37*
G36*
G01X108441Y62600D02*
X106168D01*
Y64004D01*
X109770D01*
Y63714D01*
X110812D01*
Y62212D01*
X109768D01*
Y61976D01*
X109214D01*
G02X108832Y62285I1J391D01*
G03X108441Y62600I-391J-85D01*
G37*
G36*
G01X375904Y-439648D02*
G02Y-436642I0J1503D01*
G01X379304D01*
G02Y-439648I0J-1503D01*
G01X375904D01*
G37*
G36*
G01X375964Y380082D02*
G02X374462Y381585I1J1503D01*
G02X375192Y382874I1503J0D01*
G01Y386030D01*
X380116D01*
Y382886D01*
G02X380866Y381585I-753J-1301D01*
G02X379364Y380082I-1502J-1D01*
G01X375964D01*
G37*
G36*
G01X375152Y63954D02*
Y67098D01*
G02X374402Y68399I753J1301D01*
G02X375904Y69902I1502J1D01*
G01X379304D01*
G02X380806Y68399I-1J-1503D01*
G02X380076Y67110I-1503J0D01*
G01Y63954D01*
X375152D01*
G37*
G36*
G01X375964Y10810D02*
G02X374462Y12313I1J1503D01*
G02X375192Y13602I1503J0D01*
G01Y16758D01*
X380116D01*
Y13614D01*
G02X380866Y12313I-753J-1301D01*
G02X379364Y10810I-1502J-1D01*
G01X375964D01*
G37*
G36*
G01X375124Y-164318D02*
Y-161174D01*
G02X374374Y-159873I753J1301D01*
G02X375876Y-158370I1502J1D01*
G01X379276D01*
G02X380778Y-159873I-1J-1503D01*
G02X380048Y-161162I-1503J0D01*
G01Y-164318D01*
X375124D01*
G37*
G36*
G01X375964Y-217462D02*
G02Y-214456I0J1503D01*
G01X379364D01*
G02Y-217462I0J-1503D01*
G01X375964D01*
G37*
G36*
G01X397080Y-122524D02*
G02Y-119518I0J1503D01*
G01X400480D01*
G02Y-122524I0J-1503D01*
G01X397080D01*
G37*
G36*
G01X396992Y-465710D02*
G02Y-462704I0J1503D01*
G01X400392D01*
G02Y-465710I0J-1503D01*
G01X396992D01*
G37*
G54D57*
X403692Y-481375D03*
X393692D03*
Y-456375D03*
X403692D03*
X382604Y-455313D03*
X372604D03*
Y-430313D03*
X382604D03*
X382664Y373753D03*
X372664D03*
Y398753D03*
X382664D03*
X393750Y272050D03*
X403750D03*
Y247050D03*
X393750D03*
Y200538D03*
X403750D03*
Y225538D03*
X393750D03*
X393780Y-128853D03*
X403780D03*
Y-103853D03*
X393780D03*
X403750Y-57222D03*
X393750D03*
Y-82222D03*
X403750D03*
X372604Y76231D03*
X382604D03*
Y51231D03*
X372604D03*
X413750Y-57222D03*
Y-82222D03*
X382664Y4481D03*
X372664D03*
Y29481D03*
X382664D03*
X403750Y398810D03*
X413750D03*
Y423810D03*
X403750D03*
X413750Y200538D03*
Y225538D03*
Y272050D03*
Y247050D03*
X372664Y-223791D03*
X382664D03*
Y-198791D03*
X372664D03*
X393750Y398810D03*
Y423810D03*
X372576Y-152041D03*
X382576D03*
Y-177041D03*
X372576D03*
G54D53*
X65945Y297776D03*
G54D47*
X45276Y18465D03*
X17716D03*
X291733Y20040D03*
X264173D03*
G54D51*
X336615Y18465D03*
X309055D03*
G54D52*
X144685Y297776D03*
G54D50*
X164751Y73126D03*
Y70074D03*
X168687D03*
Y73126D03*
G54D49*
X162782Y70074D03*
Y73126D03*
X170656Y70074D03*
Y73126D03*
G54D54*
X102190Y64975D03*
X56482Y455094D03*
G54D48*
X128575Y61037D03*
Y68911D03*
G54D55*
X63569Y455094D03*
G54D46*
X-58189Y454331D03*
X27300Y68200D03*
X340639Y432809D03*
X464567Y-498031D03*
Y454331D03*
G54D58*
X398760Y261279D03*
X408740Y211309D03*
X398740Y409581D03*
X408760Y-67993D03*
G54D56*
X105315Y186571D03*
G54D19*
X19200Y102700D03*
X12500Y102000D03*
X19100Y187420D03*
X15922Y224568D03*
Y227168D03*
X18422Y224568D03*
Y227168D03*
X17065Y255712D03*
X13736Y299891D03*
Y303280D03*
X13869Y352239D03*
X14000Y401700D03*
Y406700D03*
Y404200D03*
X17700Y427600D03*
X14600Y422500D03*
X14700Y425000D03*
X25200Y116300D03*
X31890Y110400D03*
X23736Y127758D03*
Y130758D03*
X32236Y127758D03*
Y130758D03*
X21000Y227000D03*
Y224500D03*
X24705Y258767D03*
X22237Y304626D03*
X30638Y304602D03*
X22237Y301237D03*
X30638Y301213D03*
X30700Y315500D03*
X33000Y318700D03*
X23810Y322534D03*
X31300Y329900D03*
X31000Y342500D03*
X26300Y374400D03*
X36200Y368400D03*
X31600Y379600D03*
X32700Y395381D03*
X20600Y428900D03*
X25202Y425329D03*
X29400Y430900D03*
X23677Y422419D03*
X31500Y428500D03*
X32100Y432800D03*
X45500Y41500D03*
X35304Y58317D03*
X45500Y92500D03*
X40340Y100710D03*
X45001Y95144D03*
X48500Y112559D03*
X40940D03*
X40736Y127758D03*
Y130758D03*
X49236Y127758D03*
Y130758D03*
X39408Y195990D03*
X47948Y201000D03*
X39900Y211000D03*
X39493Y222932D03*
X41993D03*
X44149Y227332D03*
X39493Y220332D03*
X41993D03*
X44149Y224732D03*
X48059Y214825D03*
X48023Y217860D03*
X39800Y213800D03*
X35700Y218000D03*
X35600Y241200D03*
Y238200D03*
X51500Y258200D03*
X37485Y258807D03*
X41100Y248900D03*
X46220Y277170D03*
X47440Y304225D03*
X39039Y301299D03*
X47440Y301336D03*
X39039Y304278D03*
X50950Y318050D03*
X43500Y317100D03*
X48420Y321616D03*
X44200Y332000D03*
X44525Y324000D03*
X39100Y321600D03*
X44481Y328760D03*
X38560Y329739D03*
X35500Y340500D03*
Y335000D03*
X44220Y341008D03*
X44500Y344000D03*
X37400Y359900D03*
X44500Y348000D03*
X44525Y360000D03*
X35100Y352400D03*
X44500Y351600D03*
X35900Y363025D03*
X37800Y371225D03*
X44525Y364000D03*
Y368000D03*
X37300Y375000D03*
X44525Y376000D03*
X37875Y377925D03*
X44525Y387800D03*
X37735Y391200D03*
X44525Y391650D03*
X35101Y381610D03*
X44525Y384000D03*
X37020Y385600D03*
X47075Y391730D03*
X44500Y380000D03*
X44490Y397850D03*
X44525Y394150D03*
X36911Y394915D03*
X37067Y398337D03*
X44341Y406480D03*
X44330Y401450D03*
X39530Y409100D03*
X42900Y412900D03*
X46100Y412700D03*
X41200Y429100D03*
X43600Y422800D03*
X42200Y435900D03*
X38000Y428800D03*
X48050Y436350D03*
X45100Y435800D03*
X46100Y422800D03*
X54200Y25400D03*
X58976Y36402D03*
X53600Y44100D03*
X56348Y36210D03*
X50710Y54724D03*
X55000Y76000D03*
X63086Y65762D03*
X52120Y78373D03*
X59240Y67242D03*
X52502Y80978D03*
X53434Y106562D03*
X53400Y102788D03*
X59945Y117795D03*
Y120630D03*
X52237Y129522D03*
X60800Y137000D03*
X61123Y133070D03*
X52876Y195712D03*
X52410Y186900D03*
X59700Y196200D03*
X52410Y190190D03*
X52050Y208760D03*
X64050Y201010D03*
X52948Y200700D03*
X58000Y217700D03*
X58823Y213531D03*
X51600Y241200D03*
X59850Y235830D03*
X51010Y233570D03*
X49700Y242900D03*
X50567Y238630D03*
X50700Y250400D03*
X61200Y282600D03*
X58900Y288075D03*
X54660Y311660D03*
X60613Y312012D03*
X60600Y318000D03*
X64230Y303210D03*
X56600Y320500D03*
Y324300D03*
X52800Y322400D03*
X63000Y324100D03*
X56600Y318000D03*
X52820Y325200D03*
X60225Y336099D03*
X57400Y345400D03*
X52900Y360000D03*
X52600Y376600D03*
X58035Y370100D03*
X54400Y374700D03*
X55294Y369729D03*
X52475Y364000D03*
X52765Y390200D03*
X59500Y394000D03*
X58620Y408779D03*
X63200Y408600D03*
X52330Y413350D03*
X59511Y424477D03*
X60622Y431273D03*
X64122D03*
X56250Y424200D03*
X52750D03*
X54100Y448600D03*
X56500Y447600D03*
X56482Y456844D03*
Y453344D03*
X63569Y456844D03*
Y453344D03*
X68500Y66500D03*
X75280Y75704D03*
X72500Y66500D03*
X74757Y89745D03*
Y92745D03*
Y86745D03*
Y83745D03*
X66830Y122329D03*
X66900Y125300D03*
X66874Y130590D03*
X72300Y159400D03*
X68600Y159160D03*
X76442Y166907D03*
X73550Y166680D03*
X67330Y169267D03*
X68960Y173300D03*
X75284Y180800D03*
X71124Y178565D03*
X75300Y183875D03*
X71146Y186489D03*
X71370Y188993D03*
X67386Y191935D03*
X67486Y188977D03*
X74046Y186490D03*
X71600Y200900D03*
X72150Y204810D03*
X76670Y208772D03*
X75000Y214000D03*
X72500D03*
X70453Y222900D03*
X74583Y217314D03*
X70900Y241500D03*
X71100Y233575D03*
X67700Y229725D03*
X68990Y257000D03*
X77010Y256645D03*
X65755Y256045D03*
X76200Y247400D03*
X73011Y246365D03*
X77384Y253769D03*
X68800Y253300D03*
X68990Y260465D03*
X77437Y262760D03*
X77900Y274700D03*
X70000Y280000D03*
X78600Y283970D03*
X75960Y284049D03*
X65100Y282475D03*
X72700Y301200D03*
X75870Y290700D03*
X78770Y290708D03*
X73400Y313700D03*
X77500Y316100D03*
X68500Y325100D03*
X81000Y321900D03*
X76900Y323000D03*
X76500Y325500D03*
X78700Y340000D03*
X78900Y336600D03*
X71700Y340600D03*
X71000Y394400D03*
X67900Y400525D03*
X79000Y395500D03*
X73976Y408665D03*
X77860Y408678D03*
X77592Y413437D03*
X69139Y413452D03*
X66319Y413492D03*
X74782Y413800D03*
X67000Y408800D03*
X69700D03*
X69030Y422653D03*
X68100Y425400D03*
X71200Y431700D03*
X72150Y424199D03*
X75650D03*
X77600Y431400D03*
X79010Y445750D03*
X72800Y437900D03*
X88000Y66500D03*
X84500D03*
X90151Y68985D03*
X91358Y89745D03*
Y92745D03*
Y86745D03*
Y83745D03*
X86700Y119100D03*
X92500Y116200D03*
X89256Y135056D03*
X86100Y153340D03*
X89170Y141540D03*
X89200Y138800D03*
X86100Y155840D03*
X83410Y161020D03*
X86100Y158390D03*
X83520Y158520D03*
X81500Y176515D03*
X80788Y190812D03*
X82370Y197010D03*
X91300Y252900D03*
X80300Y243700D03*
X80270Y247830D03*
X90800Y258225D03*
X83500Y266900D03*
X84016Y258230D03*
X91500Y267000D03*
X92300Y282100D03*
X90923Y293520D03*
X85500Y326700D03*
X92698Y323224D03*
X93288Y330289D03*
X81900Y337100D03*
X81700Y342600D03*
X90500Y397600D03*
X82500D03*
X89487Y408435D03*
X87600Y414500D03*
X87800Y410300D03*
X84801Y409760D03*
X92500Y408630D03*
X86481Y407871D03*
X96030Y409400D03*
X81552Y409660D03*
X84320Y430510D03*
X93259Y424200D03*
X88565Y426535D03*
X79600Y426400D03*
X81990Y448085D03*
X85490D03*
X92870Y437831D03*
X89700Y437900D03*
X92801Y452793D03*
X107000Y44500D03*
X102190Y63225D03*
X104600Y50501D03*
X98500Y66500D03*
X102190Y66725D03*
X111000Y77000D03*
X104500Y73500D03*
X107124Y71004D03*
X108800Y91900D03*
X104425Y82500D03*
X110950Y82050D03*
X106000Y91900D03*
X111075Y104600D03*
X100360Y116500D03*
X102999Y131799D03*
X108270Y138630D03*
X95950Y152900D03*
X95944Y149687D03*
X98720Y236980D03*
X103580Y237400D03*
X106600Y253689D03*
X95300Y247100D03*
X97177Y263320D03*
X102600Y267000D03*
X107200Y265000D03*
X106800Y262076D03*
X106574Y280028D03*
X106100Y282900D03*
X100700Y293600D03*
X108551Y294241D03*
X99990Y311200D03*
Y307900D03*
X105100Y309300D03*
X94400Y311100D03*
Y307200D03*
X100500Y328547D03*
X105755Y327719D03*
X103000Y323800D03*
X95060Y327625D03*
X106852Y323292D03*
X97800Y325700D03*
X99026Y338368D03*
X103180Y336286D03*
X108108Y395100D03*
X98100Y412400D03*
X105500Y418200D03*
X100457Y409100D03*
X108701Y418300D03*
X98300Y407600D03*
X108336Y411547D03*
X108500Y408680D03*
X109048Y425853D03*
X104112Y422946D03*
X103461Y425875D03*
X95845Y424755D03*
X106700Y447730D03*
X95770Y437920D03*
X95870Y445483D03*
X99370D03*
X103900Y447640D03*
X96301Y452793D03*
X119000Y44600D03*
X115000Y44500D03*
X125800Y47330D03*
X112800Y60400D03*
X112600Y52800D03*
X118500Y75500D03*
X116500Y74000D03*
X109121Y69500D03*
X119700Y89200D03*
X123710Y82300D03*
X123740Y79791D03*
X115025Y104800D03*
X123325Y111000D03*
X120724Y108937D03*
X109350Y115501D03*
X109200Y118500D03*
X120500Y115525D03*
X109200Y128500D03*
X118990Y131580D03*
X109670Y136060D03*
X118692Y137304D03*
X120800Y147200D03*
X117800D03*
X113000Y160700D03*
X115400Y159500D03*
X113000Y158000D03*
X122156Y157844D03*
X122900Y170100D03*
X123120Y213088D03*
X123790Y227656D03*
X123690Y230156D03*
X122876Y242800D03*
X117840Y242200D03*
X121200Y234890D03*
X112200Y234520D03*
X116143Y230790D03*
X112900Y239200D03*
X111400Y254680D03*
X122876Y245300D03*
X120020Y254430D03*
X119105Y251511D03*
X117400Y266500D03*
X109800Y264928D03*
X111600Y262730D03*
X111100Y273700D03*
X111600Y284000D03*
X120070Y273700D03*
X115000D03*
X122957Y300991D03*
X123100Y295974D03*
X120600Y293471D03*
X110565Y296331D03*
X124935Y324900D03*
X115535Y335235D03*
X124300Y348800D03*
X115600Y337900D03*
X114700Y351200D03*
X121200Y359200D03*
X111330Y357800D03*
X120200Y361600D03*
X114700Y348500D03*
X111460Y361770D03*
X111950Y371200D03*
X122047Y372260D03*
X125650Y368650D03*
X122330Y364670D03*
X111869Y365454D03*
X121175Y385125D03*
X119200Y389700D03*
X117410Y381350D03*
X110900Y378500D03*
X123100Y390600D03*
X119200Y406175D03*
X122600Y394600D03*
X119026Y393332D03*
X119791Y412301D03*
X112800Y421600D03*
X113000Y416200D03*
X116632Y411500D03*
X122498Y419675D03*
X112796Y412490D03*
X119500Y433600D03*
X111510Y434710D03*
X121700Y424005D03*
X123170Y433200D03*
X126425Y57000D03*
X133000Y59900D03*
X140730Y72600D03*
X130500Y74700D03*
X129300Y82650D03*
X131470Y81260D03*
X129500Y91475D03*
X131528Y114271D03*
X135500Y138000D03*
Y135000D03*
X134400Y127652D03*
X132828Y138400D03*
X133500Y146800D03*
X138458Y146458D03*
X132500Y167300D03*
X126500Y158000D03*
X133690Y158100D03*
X136190D03*
X126500Y174000D03*
X137900Y179160D03*
X135300Y175100D03*
X125700Y183700D03*
X129810Y191310D03*
X124338Y204742D03*
X124779Y201633D03*
X126153Y199079D03*
X135000Y221200D03*
X132500Y221900D03*
X138100Y213600D03*
X134891Y225171D03*
X124226Y225194D03*
X134358Y230069D03*
X130167Y234733D03*
X138000Y244600D03*
X133000Y256100D03*
X128760Y265726D03*
X127600Y259700D03*
X135315Y279813D03*
X125100Y273720D03*
X128760Y273701D03*
X137083Y278045D03*
X137196Y274491D03*
X132420Y273811D03*
X138600Y295900D03*
X124100Y311100D03*
X136100Y334000D03*
X129800Y325800D03*
X138590Y345710D03*
X124400Y345300D03*
X125910Y335006D03*
X125900Y337600D03*
X133300Y334100D03*
X136000Y341000D03*
X133000Y361500D03*
X132600Y350090D03*
X124350Y352450D03*
X129776Y374500D03*
X138700Y376600D03*
X126340Y382700D03*
X125174Y393916D03*
X135300Y399900D03*
X137900Y399500D03*
X131540Y394690D03*
X132700Y402700D03*
X133500Y409110D03*
X129135Y410250D03*
X133070Y420874D03*
X134300Y416414D03*
X136230Y423935D03*
X128866Y433066D03*
X135350Y433016D03*
X124500Y424005D03*
X132070Y433110D03*
X133572Y423935D03*
X125930Y433110D03*
X138750Y451500D03*
Y454500D03*
X152800Y75600D03*
X145000Y90700D03*
X145100Y87400D03*
X142400Y91300D03*
X141100Y86500D03*
X148819Y123197D03*
X143400Y121700D03*
X141220Y123070D03*
X147600Y117000D03*
X151800Y116500D03*
X152800Y111600D03*
X148819Y125697D03*
X149800Y138100D03*
Y135100D03*
X145185Y134214D03*
X142892Y136645D03*
X143269Y150456D03*
X150155Y145086D03*
X152556Y147683D03*
X148429Y147682D03*
X144500Y169570D03*
X146300Y161010D03*
X140554Y168887D03*
X153200Y170990D03*
X140554Y171688D03*
X146882Y177501D03*
X150619Y178646D03*
X145296Y188835D03*
X140830Y192530D03*
X153051Y187354D03*
X150005Y184973D03*
X149100Y189963D03*
X144280Y195130D03*
X151940Y203710D03*
X151900Y213200D03*
X143980Y199674D03*
X147800Y200789D03*
X140903Y199421D03*
X143742Y203395D03*
X152500Y199500D03*
X145500Y227700D03*
X142702Y227817D03*
X153100Y234800D03*
X149862Y243788D03*
X142085Y230549D03*
X151040Y237870D03*
X145250Y256890D03*
X145580Y248082D03*
X141280Y256310D03*
X149215Y267745D03*
X152400Y284400D03*
X150240Y277940D03*
X152500Y289425D03*
X150293Y302117D03*
X147500Y289405D03*
X141890Y310570D03*
X151320Y322700D03*
X148600Y336300D03*
X142202Y334000D03*
X142300Y336700D03*
X144800D03*
X144700Y334100D03*
X153419Y341978D03*
X143945Y354146D03*
X148316Y359086D03*
X141045Y355309D03*
X150900Y360325D03*
X151695Y357900D03*
X149500Y356700D03*
X141000Y358500D03*
X145703Y370700D03*
X139200Y372510D03*
X149000Y383070D03*
X152100Y378400D03*
X152500Y382600D03*
X150820Y387325D03*
X141520Y399700D03*
X139400Y392460D03*
X151265Y399500D03*
X142511Y393690D03*
X153079Y412000D03*
X149600Y410500D03*
X139700Y415100D03*
X150000Y414750D03*
X143000Y414600D03*
X140600Y412300D03*
X148060Y423500D03*
X148100Y433400D03*
X152200Y423100D03*
X148041Y426700D03*
X138987Y423935D03*
X151398Y449930D03*
X158246Y78872D03*
X156710Y73420D03*
X163423Y96281D03*
X159923D03*
X166200Y105500D03*
X155530Y116640D03*
X156286Y124903D03*
X156200Y111600D03*
X162657Y117297D03*
X154050Y137100D03*
X159000Y135000D03*
X166700Y132360D03*
X156406Y129203D03*
X162419Y131032D03*
X166733Y128700D03*
X155325Y139440D03*
X153954Y145086D03*
X161900Y150500D03*
X165690Y149622D03*
X159328Y160847D03*
X156481Y155933D03*
X162200Y158200D03*
X159900Y155600D03*
X161240Y177820D03*
X161237Y181735D03*
X156467Y203500D03*
X162594Y212585D03*
Y210085D03*
X166140Y205955D03*
X165381Y201274D03*
X153744Y217435D03*
X153800Y214900D03*
X162653Y218843D03*
X159643Y226484D03*
X162200Y221376D03*
X163500Y229184D03*
X167200Y222600D03*
X161200Y233600D03*
X165500Y236100D03*
X157200Y240000D03*
X156970Y255000D03*
X165013Y254986D03*
X160973D03*
X164500Y266000D03*
X160590Y263300D03*
X156970Y263250D03*
X164800Y263300D03*
X158750Y284949D03*
X168392Y298493D03*
X160850Y301344D03*
X168300Y301100D03*
X162100Y291600D03*
X161400Y307600D03*
X162160Y313560D03*
X170800Y317600D03*
X164500Y314800D03*
X155000Y321100D03*
X168557Y341221D03*
X158459Y340898D03*
X158467Y344067D03*
X161300Y354600D03*
X161154Y376704D03*
X156300Y376300D03*
X154500Y387350D03*
X159050Y387334D03*
X162550D03*
X165500Y386000D03*
X165501Y382800D03*
X158200Y381400D03*
X155452Y401000D03*
X160540Y416912D03*
X162100Y414000D03*
X157294Y435623D03*
X156101Y425100D03*
X167008Y430718D03*
X165500Y433100D03*
X167865Y427771D03*
X163700Y422119D03*
X159396Y449408D03*
X160700Y445550D03*
X158100Y442700D03*
X168029Y456660D03*
X157500Y453390D03*
X176900Y14625D03*
X178200Y76145D03*
X175700Y76245D03*
X179900Y91300D03*
X181960Y99260D03*
X169700Y102250D03*
X176300Y98700D03*
X172847Y96281D03*
X169347D03*
X179500Y116800D03*
X182000Y117200D03*
X171600Y114000D03*
X182865Y113706D03*
X174600Y114000D03*
X169100Y113900D03*
X182103Y132294D03*
X182108Y129094D03*
X170867Y128211D03*
X178290Y128824D03*
X174553Y128728D03*
X176550Y125210D03*
X178284Y132394D03*
X170610Y131900D03*
X174436Y132394D03*
X168800Y126800D03*
X172100Y146300D03*
X176000Y140500D03*
X172890Y153260D03*
X171700Y156900D03*
X169500Y180200D03*
X170800Y193100D03*
X172621Y208300D03*
X173800Y225400D03*
X170400Y214700D03*
X172400Y220700D03*
X175300Y240000D03*
X174400Y254736D03*
X179846Y255150D03*
X180458Y258825D03*
X174400Y251936D03*
X176900Y270100D03*
X174292Y263300D03*
X171592Y263312D03*
X168710Y272256D03*
X172977Y277000D03*
X182435Y281797D03*
X179217Y278528D03*
X168656Y275156D03*
X182232Y296424D03*
X174232Y304333D03*
X176563Y310917D03*
X176533Y314049D03*
X170550Y304050D03*
X169077Y308677D03*
X170561Y306631D03*
X181050Y332250D03*
X171098Y341224D03*
X182700Y342216D03*
X180600Y360200D03*
X177500Y369100D03*
X178850Y385634D03*
X182350D03*
X172530Y420950D03*
Y429470D03*
X184480Y429370D03*
X171400Y450600D03*
X193100Y69100D03*
X189400Y69600D03*
X184800Y100300D03*
X187700Y99000D03*
X187400Y101500D03*
X190800Y117200D03*
X193096Y115600D03*
X186891Y113991D03*
X190744Y114456D03*
X187069Y116800D03*
X184729Y115820D03*
X187435Y129623D03*
X195983Y132294D03*
X191482Y129294D03*
X195983D03*
X186200Y125600D03*
X184000Y140500D03*
X196577Y141185D03*
X189700Y140400D03*
X191693Y236370D03*
X196240Y253430D03*
X193084Y257400D03*
X194567Y255288D03*
X187400Y255700D03*
X190900Y271700D03*
X193386Y269142D03*
X184200Y264900D03*
X185000Y270700D03*
X195370Y273297D03*
X183625Y273500D03*
X196200Y278200D03*
X196100Y281820D03*
X187623Y297475D03*
X192380Y291900D03*
X196443Y294065D03*
X191199Y300200D03*
X192448Y308314D03*
X195031Y307182D03*
X194600Y313300D03*
X197853Y307200D03*
X197155Y314223D03*
X188546Y326356D03*
X190465Y344426D03*
X190600Y337900D03*
X183800Y345400D03*
X197775Y346617D03*
X194800Y341700D03*
X191408Y357451D03*
X197450Y356560D03*
X196050Y358770D03*
X191420Y354710D03*
X190965Y348090D03*
X197711Y349250D03*
X195000Y373900D03*
X187400Y379400D03*
X197400Y367600D03*
Y370250D03*
X197620Y385425D03*
X187300Y384300D03*
X197660Y390870D03*
X190050Y389140D03*
X190100Y392270D03*
X191843Y403995D03*
X189054Y397500D03*
X194500Y402600D03*
X195800Y396780D03*
X185245Y417500D03*
X190370Y422490D03*
X195000Y422540D03*
X199940Y423700D03*
X197600Y415400D03*
X190270Y409962D03*
X189762Y429177D03*
X195300Y432327D03*
X189766Y432050D03*
X189838Y434910D03*
X186720Y432490D03*
X186300Y448700D03*
X185000Y451500D03*
Y454000D03*
Y456500D03*
X191780Y453300D03*
Y456700D03*
X211400Y59238D03*
X204300Y60600D03*
X201500Y61000D03*
X209142Y53664D03*
X204100Y67400D03*
X201900Y83300D03*
X199940Y117500D03*
X211370Y117000D03*
X208200Y111760D03*
X199985Y132294D03*
X212757Y127064D03*
X212727Y129654D03*
X208627Y132394D03*
X208576Y128957D03*
X204120Y132294D03*
X200000Y128764D03*
X208500Y126057D03*
X212727Y132154D03*
X211490Y143700D03*
X205598Y140480D03*
X203542Y213254D03*
X206200Y255385D03*
X200680Y257540D03*
X206051Y247911D03*
X205500Y258300D03*
X201100Y265120D03*
X214034Y261482D03*
X201000Y262500D03*
X203090Y269229D03*
X205590Y269129D03*
X205900Y266130D03*
X204258Y286691D03*
X213258Y273265D03*
X204560Y301130D03*
X212911Y293869D03*
X206430Y298780D03*
X199729Y314565D03*
X198672Y318175D03*
X208628Y324665D03*
X200300Y328800D03*
X208000Y373240D03*
X208565Y404501D03*
X200222Y398150D03*
X213200Y399166D03*
X199880Y402846D03*
X207539Y408686D03*
X200000Y407040D03*
X205223Y422665D03*
X207278Y416022D03*
X206150Y412821D03*
X198600Y426600D03*
X202513Y434800D03*
X198405D03*
X199000Y444500D03*
X205200Y445400D03*
X213225Y442220D03*
X214306Y62233D03*
X229900Y61000D03*
X224000Y74275D03*
X218600Y92100D03*
X221300D03*
X224330Y83210D03*
X227760Y82524D03*
X219900Y101300D03*
X216400Y106400D03*
X226040Y101220D03*
X222890Y101240D03*
X215294Y117094D03*
X226887Y117297D03*
X223300Y117400D03*
X217262Y129294D03*
X225284Y132294D03*
X229342Y129240D03*
X221278Y129294D03*
X225284D03*
X217262Y132294D03*
X221278D03*
X225300Y125200D03*
X227700Y151900D03*
X221000Y243000D03*
X220100Y237200D03*
X223800Y254800D03*
X227316Y256700D03*
X215100Y244100D03*
X215500Y247111D03*
X216800Y255550D03*
X215510Y253310D03*
X225275Y246000D03*
X217500Y264000D03*
X230196Y267477D03*
X219900Y267100D03*
X220866Y272160D03*
X227232Y270539D03*
X226405Y266335D03*
X222833Y261668D03*
X219722Y286728D03*
X227841Y275773D03*
X219339Y284138D03*
X219359Y281580D03*
X226500Y273000D03*
X229220Y283250D03*
X223646Y293960D03*
X214400Y303997D03*
X216384Y312216D03*
X228800Y312100D03*
X226100Y325065D03*
X217300Y322800D03*
X225867Y345033D03*
X225650Y337520D03*
X221000Y343800D03*
X216405Y335970D03*
X214175Y333740D03*
X228230Y340040D03*
X221000Y352000D03*
X224632Y369825D03*
X225700Y362500D03*
X213490Y373690D03*
X226710Y364815D03*
X223420Y367080D03*
X220515Y384900D03*
X222575Y387625D03*
X227206Y400100D03*
X217390Y401340D03*
X222986Y400323D03*
X220134Y400780D03*
X219050Y418850D03*
X217725Y410150D03*
X221225D03*
X226830Y435170D03*
X225000Y433100D03*
X219250Y422150D03*
X213900Y436000D03*
X217100Y436100D03*
X224000Y449100D03*
X216725Y442220D03*
X237000Y47200D03*
X234537Y74638D03*
X240000Y67400D03*
X230600Y91700D03*
X239660Y91920D03*
X232150Y82480D03*
X235630Y104990D03*
X231592Y110500D03*
X240160Y107000D03*
X240710Y99570D03*
X232325Y101230D03*
X236648Y100739D03*
X238900Y114800D03*
X234500Y117500D03*
X230293Y117417D03*
X239900Y117550D03*
X239206Y112300D03*
X233511Y132594D03*
X234900Y126100D03*
X229396Y132294D03*
X233511Y129594D03*
X242500Y129000D03*
X242195Y141003D03*
X232384Y148884D03*
X230535Y244564D03*
X237700Y257387D03*
X237730Y248085D03*
X242690Y255300D03*
X230000Y255700D03*
X232300Y261200D03*
X239298Y268800D03*
X242940Y268500D03*
X233033Y266483D03*
X229630Y264404D03*
X242087Y271427D03*
X238531Y263081D03*
X231900Y272700D03*
X241188Y279347D03*
X241263Y282654D03*
X234500Y293500D03*
X242700Y306800D03*
X240500Y316575D03*
X236688Y311217D03*
X238400Y304200D03*
X228800Y305500D03*
X235400Y303800D03*
X242592Y330683D03*
X243010Y323400D03*
X230445Y325945D03*
X235000Y335300D03*
X231689Y334896D03*
X233500Y346911D03*
Y343911D03*
X231500Y352500D03*
X233650Y359628D03*
X233800Y354300D03*
X230287Y373100D03*
X232470Y382280D03*
X233600Y377300D03*
X233790Y384490D03*
X239750Y394970D03*
X236670Y394550D03*
X241231Y407285D03*
X236860Y407300D03*
X229900Y436600D03*
X236900Y440565D03*
X239500Y447750D03*
X235400Y451600D03*
X231250Y447000D03*
X235200Y449100D03*
X231400Y449500D03*
X241436Y445784D03*
X240200Y450650D03*
X236221Y454400D03*
X240010Y456000D03*
X240210Y453400D03*
X231400Y452000D03*
X252925Y54000D03*
X249475Y55812D03*
X256000Y56000D03*
X246200Y74600D03*
X253000Y77500D03*
X250000Y73000D03*
X255000Y82700D03*
X257800Y82800D03*
X256900Y87300D03*
X251200Y93800D03*
X251900Y100100D03*
X255213Y106099D03*
X249988Y105792D03*
X246488D03*
X244208Y97302D03*
X247200Y117400D03*
X253100Y119900D03*
X245310Y113910D03*
X245500Y127800D03*
X245520Y130600D03*
X258500Y146400D03*
X251354Y152877D03*
X249300Y237600D03*
X247689Y247929D03*
X253110Y254909D03*
X253100Y257800D03*
X252639Y247885D03*
X256700Y263800D03*
X255700Y260000D03*
X247470Y269990D03*
X250288Y273581D03*
X251459Y286542D03*
Y283542D03*
X257145Y279700D03*
X246514Y294325D03*
Y296825D03*
X258100Y295080D03*
X254355Y300577D03*
X247923Y316400D03*
X245900Y305000D03*
X257900Y312100D03*
X248900Y304900D03*
X247923Y319000D03*
X253320Y323327D03*
X256124Y336355D03*
X243750Y369730D03*
X243700Y372730D03*
X244790Y375910D03*
X248800Y385700D03*
X249400Y410300D03*
X252350Y412850D03*
X257810Y435100D03*
X246700Y451500D03*
X246500Y448500D03*
X243375Y448375D03*
X246700Y454100D03*
X259000Y47500D03*
X267939Y41122D03*
X268500Y45500D03*
X259894Y90072D03*
X263102Y91725D03*
X272505Y83545D03*
X260050Y87026D03*
X265801Y106040D03*
X260970Y98600D03*
X258713Y106099D03*
X264989Y101732D03*
X271602Y121400D03*
X269561Y130987D03*
X271300Y132900D03*
X269493Y138604D03*
X260200Y132395D03*
X260388Y125001D03*
X268442Y153299D03*
X265942D03*
Y150799D03*
X268442D03*
X269004Y144450D03*
Y141950D03*
X269133Y164982D03*
X265226D03*
X268339Y222126D03*
X272300Y251000D03*
X258628Y247600D03*
X258475Y254872D03*
X267100Y265000D03*
X269016Y266991D03*
X259500Y263700D03*
X262730Y267600D03*
X258000Y266300D03*
X266600Y268700D03*
X262700Y265100D03*
X258000Y284900D03*
X262100Y280700D03*
X266250Y297900D03*
X266200Y294800D03*
X261500Y290440D03*
X266300Y307500D03*
X262310Y311225D03*
X264265Y315817D03*
X261300Y334100D03*
X271100Y346575D03*
X259420Y343230D03*
Y340630D03*
X273580Y354250D03*
X271990Y362360D03*
X265320Y392290D03*
X274190Y408900D03*
X265100Y395100D03*
X272400Y392400D03*
X269700Y411379D03*
X271500Y418300D03*
X267100Y432900D03*
X263800Y430300D03*
X272999Y430500D03*
X271710Y449840D03*
X266727Y443185D03*
X261700Y439700D03*
X265130Y440070D03*
X261100Y443500D03*
X269561Y456044D03*
X286000Y47000D03*
X277000Y51665D03*
X274500Y58000D03*
X279934Y51688D03*
X279800Y72700D03*
X290000Y82000D03*
X273400Y92800D03*
X276400Y92300D03*
X287578Y84092D03*
X283500Y89500D03*
X277505Y83545D03*
X282505D03*
X278300Y95019D03*
X274760Y105140D03*
X275386Y102710D03*
X280910Y102880D03*
X288116Y120306D03*
X285250Y117250D03*
X274200Y109500D03*
X280400Y126000D03*
X283500D03*
X275960Y126010D03*
X273450Y125050D03*
X287796Y131542D03*
X288280Y126212D03*
X280616Y150971D03*
X283616D03*
X287555Y142419D03*
X285899Y153542D03*
X283399D03*
X279457Y171318D03*
X279983Y235254D03*
X282483D03*
X283974Y251372D03*
X286800Y251400D03*
X276200Y251500D03*
X280082Y251328D03*
X280030Y267098D03*
Y264098D03*
X284357Y267027D03*
Y264027D03*
X285911Y269899D03*
X281889D03*
X287755Y287538D03*
X282911Y279569D03*
X285911D03*
X287507Y301596D03*
X281300Y308800D03*
X287050Y305850D03*
X289939Y309060D03*
X276660Y316900D03*
X273355Y330001D03*
X286372Y320700D03*
X289600Y322253D03*
X286372Y326768D03*
X285860Y336131D03*
X277500Y348469D03*
X275520Y357910D03*
X277290Y355820D03*
X277572Y351198D03*
X287761Y366200D03*
X287500Y376900D03*
X276145Y366455D03*
X276400Y370400D03*
X283664Y379236D03*
X273100Y381500D03*
X283973Y382553D03*
X285191Y390840D03*
X287630Y389378D03*
X275700Y403500D03*
X277700Y406100D03*
X287476Y396680D03*
X278900Y421400D03*
X281300Y416200D03*
X277700Y412580D03*
X287500Y416100D03*
X278409Y433722D03*
X276400Y431810D03*
X275100Y427682D03*
X274619Y424725D03*
X283622Y447155D03*
X275138Y451215D03*
X276632Y439502D03*
X283674Y449975D03*
X283715Y452769D03*
X297466Y51521D03*
X300425Y54516D03*
X290000Y67975D03*
X297575Y73738D03*
X293773Y73530D03*
X300070Y84000D03*
X294600Y106900D03*
X298575Y101900D03*
X304000Y116500D03*
X294800Y111800D03*
X298975Y118900D03*
X301000Y121016D03*
X300500Y125000D03*
X295075Y119100D03*
X301000Y129900D03*
X290200Y129500D03*
X298005Y151118D03*
Y148618D03*
Y146118D03*
X292204Y142610D03*
X301936Y143897D03*
X296734Y216079D03*
X290586Y234844D03*
X288086D03*
X301120Y235626D03*
Y238765D03*
X299138Y244513D03*
X291500Y287670D03*
Y285170D03*
X298840Y279640D03*
X291000Y297700D03*
X291300Y315900D03*
X290120Y339370D03*
X290000Y335600D03*
X300700Y341300D03*
X295500Y354920D03*
X296780Y371500D03*
X298152Y393332D03*
X292700Y403700D03*
X291623Y447747D03*
X291703Y450819D03*
X295729Y453912D03*
Y456912D03*
Y459912D03*
X297738Y452418D03*
Y458418D03*
Y455418D03*
X316025Y60200D03*
X309570Y84000D03*
X316066Y108407D03*
X315100Y116400D03*
X307400Y122300D03*
X315900Y125900D03*
X313800Y124300D03*
X307560Y128500D03*
X305936Y143897D03*
X309936D03*
X313936D03*
X307487Y219503D03*
X304987D03*
X310449Y218617D03*
X317110Y219140D03*
X309521Y235352D03*
Y238741D03*
X305000Y252400D03*
X307600Y252300D03*
X307800Y259200D03*
X312272Y282107D03*
X302800Y286200D03*
X311670Y285160D03*
X302879Y282487D03*
Y279686D03*
X309700Y294789D03*
X306500Y301500D03*
X303000Y309200D03*
X306200Y308800D03*
X312300Y340700D03*
X308906Y362637D03*
X314340Y373296D03*
X311925Y366475D03*
X308926Y401900D03*
X321800Y60055D03*
X322500Y102900D03*
X320500Y100400D03*
X324011Y118843D03*
X324023Y121943D03*
Y115643D03*
X320765Y114582D03*
X320938Y122677D03*
X318000Y117200D03*
X331741Y138243D03*
Y125796D03*
X317936Y143897D03*
X323509Y153377D03*
X329005Y152657D03*
X328087Y141608D03*
X331641Y141743D03*
X321600Y142100D03*
X331405Y164911D03*
Y159911D03*
Y154911D03*
Y167411D03*
Y179911D03*
Y174911D03*
Y169911D03*
Y182926D03*
Y172411D03*
Y189911D03*
X320054Y195163D03*
X326932Y205685D03*
X326733Y209885D03*
X321045Y210257D03*
X320937Y212839D03*
X326733Y201485D03*
X320054Y198663D03*
X326731Y213648D03*
X320931Y215387D03*
X317922Y238717D03*
Y235328D03*
X326323Y235304D03*
Y238693D03*
X327162Y278972D03*
X325007Y328608D03*
Y326008D03*
X327704Y328635D03*
Y326035D03*
X325007Y323508D03*
X327704Y323535D03*
X329925Y356016D03*
X325900Y365643D03*
X326100Y375717D03*
X326200Y370681D03*
X331500Y383300D03*
X326375Y380724D03*
X325593Y406500D03*
X329093D03*
X318593D03*
X322093D03*
X339900Y69100D03*
Y66000D03*
X339908Y104577D03*
Y108593D03*
X342200Y100500D03*
X342180Y106900D03*
X339908Y112609D03*
X339369Y151952D03*
X339939Y162911D03*
X339812Y173380D03*
X339800Y182926D03*
X337400Y193449D03*
X334724Y238669D03*
Y235280D03*
X337467Y236984D03*
X336461Y283202D03*
X340612Y278972D03*
X339700Y293000D03*
X347100Y313700D03*
X345500Y342690D03*
X335475Y358500D03*
Y367500D03*
X335708Y372008D03*
X335500Y380000D03*
X375904Y-438145D03*
X375964Y-215959D03*
X375876Y-159873D03*
X375964Y12313D03*
X375904Y68399D03*
X375964Y381585D03*
X379304Y-438145D03*
X379364Y-215959D03*
X379276Y-159873D03*
X379364Y12313D03*
X379304Y68399D03*
X379364Y381585D03*
X396992Y-464207D03*
X400392D03*
X397080Y-121021D03*
X400480D03*
G54D23*
X23819Y339154D03*
Y359154D03*
Y369154D03*
Y379154D03*
Y389154D03*
Y399154D03*
Y409154D03*
X65709Y42244D03*
Y52244D03*
X75709Y42244D03*
Y52244D03*
X95709Y42244D03*
X85709D03*
Y52244D03*
G54D25*
X63898Y24764D03*
X73898D03*
X90472D03*
X100472D03*
X117047D03*
X127047D03*
X211142D03*
X237717D03*
X247717D03*
G54D28*
X62458Y346425D03*
Y343275D03*
Y355873D03*
X58564Y354280D03*
X65607Y352724D03*
Y359023D03*
Y371584D03*
X75056Y346425D03*
X68757D03*
X81355D03*
X78206Y349574D03*
X71906D03*
X68757D03*
X78206Y359023D03*
X75056Y352724D03*
Y349574D03*
X78206Y355873D03*
X65607D03*
X68757Y362173D03*
Y359023D03*
X71906D03*
X75056Y355873D03*
X71906Y352724D03*
X68757Y355873D03*
X78206Y374733D03*
Y362173D03*
X75056D03*
X71906Y371584D03*
X75056Y365322D03*
X71906D03*
X68757D03*
Y371584D03*
X75056Y374733D03*
X71906D03*
X68757D03*
X65607D03*
X71906Y362173D03*
X78206Y365322D03*
Y371584D03*
X68757Y377883D03*
X78206Y381033D03*
X65607D03*
X71906Y377883D03*
X65607Y384182D03*
X68719Y381033D03*
X78206Y377883D03*
X71906Y387332D03*
X71869Y381033D03*
X71906Y384182D03*
X87617Y352724D03*
X90766Y349574D03*
X93916Y352724D03*
X81355Y355873D03*
X90766Y352724D03*
X87617Y349574D03*
X90766Y355873D03*
X87617D03*
X90766Y359023D03*
X81355Y349574D03*
X87617Y359023D03*
X90766Y374733D03*
Y362173D03*
X81355D03*
X87617D03*
X81355Y374733D03*
X87617D03*
X90766Y371584D03*
Y365322D03*
X81355Y377883D03*
Y387332D03*
Y384182D03*
X87617D03*
X90766Y377883D03*
X87617Y390481D03*
X81355Y381033D03*
X87617Y387332D03*
X90766Y381033D03*
X87617Y377883D03*
X90766Y390481D03*
Y387332D03*
Y384182D03*
X92360Y394175D03*
X89210D03*
X103365Y346425D03*
X106564Y346400D03*
X100253Y346387D03*
X93916Y349574D03*
X97066D03*
X106515Y352724D03*
X106514Y349574D03*
X97066Y352724D03*
X100215Y355873D03*
X93916D03*
X100215Y349574D03*
Y387332D03*
X97066D03*
X93916Y384182D03*
X97066D03*
X100215Y381033D03*
X93916D03*
Y387332D03*
X166300Y212300D03*
X181495Y153449D03*
X175196Y159748D03*
X178346Y156599D03*
X181495Y159748D03*
X175196Y156599D03*
X181495D03*
Y166047D03*
X184645D03*
X181495Y162898D03*
X178346Y159748D03*
X181495Y178646D03*
Y175496D03*
X184645Y181795D03*
X181495D03*
Y172347D03*
X184645Y175496D03*
X174569Y180202D03*
X178346Y175496D03*
X175196Y172347D03*
X173000Y170200D03*
X181495Y169197D03*
Y184945D03*
Y197506D03*
X178346D03*
Y191244D03*
X181495D03*
X175196Y197506D03*
X174336Y192800D03*
X181495Y188095D03*
X178346D03*
X175196Y200655D03*
X178346Y210104D03*
X181495Y203805D03*
Y206955D03*
X175196Y210104D03*
X178346Y206955D03*
X175196D03*
Y203805D03*
X178346D03*
X171836Y200655D03*
Y198300D03*
X181495Y200655D03*
Y219553D03*
X175196Y213254D03*
X184645Y219553D03*
X178346Y229002D03*
X181495Y225852D03*
Y222703D03*
X184645Y229002D03*
X174600Y217800D03*
X181495Y216403D03*
X175196Y229002D03*
X181495D03*
X187794Y153449D03*
X192400Y152804D03*
X184645Y153449D03*
X197243Y166047D03*
X194094Y162898D03*
X197243Y159748D03*
X194094D03*
X197243Y162898D03*
X184645Y156599D03*
X187794Y162898D03*
Y166047D03*
X184645Y162898D03*
Y159748D03*
X190944Y162898D03*
Y159748D03*
X194094Y166047D03*
X190944D03*
X200393Y162898D03*
X187794Y156599D03*
Y178646D03*
X194094Y169197D03*
X190944Y172347D03*
Y175496D03*
X197243D03*
X190944Y178646D03*
Y181795D03*
X187794Y175496D03*
X184645Y178646D03*
X190944Y169197D03*
X187794Y172347D03*
X184645Y169197D03*
Y172347D03*
X187794Y169197D03*
X197243Y184945D03*
X190944Y197506D03*
Y184945D03*
Y188095D03*
Y191244D03*
X187794Y197506D03*
Y184945D03*
X184645Y197506D03*
Y184945D03*
Y191244D03*
Y188095D03*
X190944Y200655D03*
Y210104D03*
Y203805D03*
X187794Y200655D03*
X184645Y210104D03*
Y200655D03*
Y203805D03*
X187794Y210104D03*
X190944Y219553D03*
X194094Y222703D03*
X200393Y229002D03*
X194094Y225852D03*
X187794D03*
Y219553D03*
X190944Y213254D03*
Y222702D03*
X200393Y222703D03*
X197243Y225852D03*
Y222703D03*
X184645Y225852D03*
X187794Y222703D03*
X184645D03*
Y213254D03*
X194094Y219553D03*
X187794Y229002D03*
X197243Y235301D03*
X194094Y229002D03*
X197243D03*
Y232151D03*
X209842Y153449D03*
Y159748D03*
X206692Y156599D03*
X203542Y166047D03*
X206692Y162898D03*
X203542D03*
X200393Y159748D03*
X209842Y166047D03*
Y162898D03*
X212991D03*
X203542Y159748D03*
X200393Y166047D03*
X206692D03*
X212991D03*
X206692Y159748D03*
X209842Y169197D03*
X206692Y181795D03*
X203542Y175496D03*
X206692D03*
X209842D03*
X200393D03*
X212991Y184945D03*
Y197506D03*
X203542Y206955D03*
X212991Y203805D03*
X206692Y206955D03*
X209842D03*
X200393D03*
X212991Y200655D03*
Y213254D03*
X200393D03*
Y219553D03*
X212991Y222740D03*
X209842Y213254D03*
Y225852D03*
X203542Y222703D03*
X200393Y225852D03*
X206692Y219553D03*
X203542Y225852D03*
X206692Y229002D03*
X212991D03*
X203542Y219553D03*
X206692Y222703D03*
X209842D03*
X212991Y225890D03*
X206692Y225852D03*
X203542Y229002D03*
X209746Y235397D03*
X203542Y235301D03*
X209842Y232151D03*
X200393D03*
X206692D03*
X212991D03*
X209842Y229002D03*
X225658Y153369D03*
X225552Y159748D03*
X222402Y162898D03*
X219253Y166047D03*
X225552Y162898D03*
Y166047D03*
X222402D03*
X219253Y159748D03*
X222402D03*
X219253Y162898D03*
Y156599D03*
X222402D03*
Y178646D03*
X225552Y181795D03*
X214547Y174852D03*
X225552Y169197D03*
X219253D03*
X225552Y191244D03*
Y188095D03*
X222402Y191244D03*
X219253Y197506D03*
X222402D03*
X219253Y188095D03*
Y200655D03*
Y206955D03*
Y210104D03*
Y203805D03*
Y213254D03*
X228739Y222703D03*
X216141D03*
X228702Y229002D03*
X225590Y222720D03*
X216103Y219591D03*
X219253Y219553D03*
X225590Y225852D03*
X222440Y222703D03*
X225552Y219553D03*
X222402D03*
Y229002D03*
X222440Y225852D03*
X219290D03*
Y222703D03*
X225552Y229002D03*
X219253D03*
X235001Y153449D03*
X228702Y162898D03*
X238150D03*
X231851Y166047D03*
X238150D03*
X228702Y159748D03*
Y166047D03*
X238150Y156599D03*
X235001D03*
X231851D03*
Y162898D03*
Y159748D03*
X235001Y162898D03*
Y159748D03*
X238150D03*
X241300D03*
X231851Y169197D03*
Y178646D03*
X235001Y169197D03*
X241300Y175496D03*
Y178646D03*
Y172347D03*
X235001Y178646D03*
Y175496D03*
X228702Y181795D03*
Y178646D03*
X235001Y188095D03*
Y191244D03*
Y197506D03*
X241300Y184945D03*
Y197506D03*
Y188095D03*
X244450Y200655D03*
X228702D03*
X235001Y203805D03*
X231851D03*
X228702D03*
X241300Y200655D03*
Y210104D03*
X235001D03*
X231851D03*
X228702D03*
X235038Y225890D03*
X228739Y225852D03*
X238150Y222703D03*
X231889Y219591D03*
Y222740D03*
X235038D03*
X231889Y225890D03*
X228739Y216441D03*
X241338Y225890D03*
X231851Y229002D03*
X241300D03*
X239870Y237596D03*
X242870D03*
X235038Y229039D03*
X250749Y169197D03*
X247637Y162898D03*
X247599Y166047D03*
X253898Y169197D03*
X257048Y172347D03*
X250749Y181795D03*
X244450D03*
X250749Y175496D03*
Y178646D03*
X247599Y172347D03*
X244450Y175496D03*
X250749Y172347D03*
X247599Y178646D03*
X253898Y175496D03*
X244450Y178646D03*
Y172347D03*
X250749Y184945D03*
X244450Y169197D03*
Y197506D03*
X247599Y191244D03*
X257048Y197506D03*
X253898D03*
X250749D03*
X247599Y184945D03*
X244450Y188095D03*
X257048Y191244D03*
X250749Y188095D03*
X244450Y184945D03*
X250749Y191244D03*
X244450D03*
X250749Y203805D03*
X247599Y206955D03*
Y210104D03*
X250749Y206955D03*
X247599Y200655D03*
X257048Y206955D03*
X250749Y200655D03*
X257048D03*
X250749Y210104D03*
X244450Y203805D03*
X250749Y222703D03*
Y225852D03*
X253898Y219553D03*
Y222703D03*
X257048Y213254D03*
X250749D03*
X247599D03*
X253898D03*
X247637Y225852D03*
X244450Y232151D03*
X247599D03*
X253898D03*
X257048D03*
X250749Y229002D03*
X253898D03*
X250749Y235301D03*
X253898D03*
X267722Y176791D03*
X264222D03*
X271209Y177524D03*
X270472Y188488D03*
X264118Y188095D03*
X266080Y207262D03*
X262580D03*
X263580Y214593D03*
X267080D03*
X285482Y168102D03*
X273644Y174267D03*
X282975Y172975D03*
X286105Y176085D03*
X289254Y194839D03*
X286105Y185534D03*
Y194839D03*
Y204288D03*
X286106Y210587D03*
X286105Y213721D03*
X289110Y163487D03*
X292260D03*
X295410Y169786D03*
X292404Y176085D03*
X295410Y172936D03*
X289254Y172792D03*
X292260Y169643D03*
X295410Y179235D03*
X292384Y172936D03*
X289254Y176085D03*
Y182385D03*
X292260Y179235D03*
X289111D03*
X292404Y191690D03*
X289254D03*
X292404Y185534D03*
Y194983D03*
X295410Y194839D03*
X295411Y185534D03*
X289254D03*
Y197989D03*
X298714Y210477D03*
X292404Y210587D03*
Y201282D03*
X299667Y201334D03*
X292404Y213737D03*
X289254Y201139D03*
X295410Y210587D03*
X311158Y163487D03*
X308008Y166637D03*
X314307Y163487D03*
X314930Y168140D03*
Y171289D03*
Y177588D03*
X305002Y176085D03*
Y169786D03*
Y172936D03*
X308152Y169786D03*
X311158Y169643D03*
X308152Y172936D03*
Y176085D03*
Y182385D03*
X305002Y179235D03*
X308152D03*
X314930Y180738D03*
Y174439D03*
X308008Y191690D03*
X311158D03*
X308008Y188540D03*
Y185391D03*
Y198133D03*
X314307Y185534D03*
X311158Y188540D03*
X308008Y194839D03*
X311158Y197989D03*
X314307Y194839D03*
Y197989D03*
X308008Y207438D03*
X308152Y204432D03*
X305002D03*
X311158Y210587D03*
X308008Y210731D03*
X305002Y210587D03*
X314307Y201139D03*
Y204288D03*
Y210587D03*
Y213737D03*
G54D39*
X372604Y-455313D03*
Y-430313D03*
X372664Y-223791D03*
Y-198791D03*
X372576Y-177041D03*
Y-152041D03*
X372664Y4481D03*
Y29481D03*
X372604Y51231D03*
Y76231D03*
X372664Y373753D03*
Y398753D03*
X393692Y-481375D03*
X382604Y-455313D03*
X393692Y-456375D03*
X382604Y-430313D03*
X382664Y-223791D03*
Y-198791D03*
X382576Y-177041D03*
Y-152041D03*
X393780Y-128853D03*
Y-103853D03*
X393750Y-82222D03*
Y-57222D03*
X382664Y4481D03*
Y29481D03*
X382604Y51231D03*
Y76231D03*
X393750Y200538D03*
Y225538D03*
Y247050D03*
Y272050D03*
X382664Y373753D03*
X393750Y398810D03*
X382664Y398753D03*
X393750Y423810D03*
X403692Y-481375D03*
Y-456375D03*
X403780Y-128853D03*
Y-103853D03*
X403750Y-82222D03*
D03*
Y-57222D03*
D03*
Y200538D03*
D03*
Y225538D03*
D03*
Y247050D03*
D03*
Y272050D03*
D03*
Y398810D03*
D03*
Y423810D03*
D03*
X413750Y-82222D03*
Y-57222D03*
Y200538D03*
Y225538D03*
Y247050D03*
Y272050D03*
Y398810D03*
Y423810D03*
G54D14*
X3000Y8494D03*
Y28494D03*
Y48494D03*
Y68494D03*
Y88494D03*
Y108494D03*
Y128494D03*
Y148494D03*
Y168494D03*
Y188494D03*
Y208494D03*
Y228494D03*
Y248494D03*
Y268494D03*
Y288494D03*
Y308494D03*
Y342126D03*
Y362126D03*
Y382126D03*
Y402126D03*
Y422126D03*
Y442126D03*
X16626Y195848D03*
X19129D03*
Y193048D03*
X16626D03*
X19129Y204248D03*
X17000Y208017D03*
X16626Y198648D03*
Y201448D03*
X19129Y198648D03*
Y201448D03*
X16626Y204248D03*
X6200Y312900D03*
X13827Y325310D03*
X21250Y206220D03*
X36599Y189016D03*
X37360Y194050D03*
X37823Y198346D03*
X48035Y191535D03*
X47714Y212227D03*
X48940Y204871D03*
X52155Y121218D03*
X60112Y113992D03*
X222402Y169197D03*
X238188Y225852D03*
X228739Y213254D03*
X250749Y159748D03*
X244020Y235518D03*
X244487Y229002D03*
X268510Y179088D03*
X301120Y226421D03*
Y229810D03*
X302687Y275497D03*
X296938Y325700D03*
X311301Y182385D03*
X309521Y226397D03*
Y229786D03*
X314969Y456527D03*
X329297Y134594D03*
Y129890D03*
X321276Y134532D03*
X321349Y130044D03*
X326323Y226349D03*
X317922Y226373D03*
X326323Y229738D03*
X317922Y229762D03*
X373480Y-210223D03*
X370965D03*
Y-206970D03*
X376406Y-206985D03*
X373480Y-206970D03*
X372271Y-213263D03*
X373480Y18049D03*
X370965D03*
X372271Y15009D03*
X370965Y21302D03*
X376406Y21287D03*
X373480Y21302D03*
X372271Y384281D03*
X376406Y390559D03*
X373480Y387321D03*
Y390574D03*
X370965Y387321D03*
Y390574D03*
X383057Y-213263D03*
X381848Y-206970D03*
X384363D03*
Y-210223D03*
X381848D03*
X378922Y-206970D03*
X392081Y-115285D03*
Y-112032D03*
X383057Y15009D03*
X384363Y18049D03*
X381848D03*
Y21302D03*
X384363D03*
X378922D03*
X391950Y214106D03*
Y217359D03*
X378922Y390574D03*
X381848D03*
Y387321D03*
X384363Y390574D03*
Y387321D03*
X383057Y384281D03*
X391950Y412378D03*
Y415631D03*
X394596Y-115285D03*
X393387Y-118325D03*
X404173D03*
X405479Y-115285D03*
X402964D03*
X397522Y-112047D03*
X394596Y-112032D03*
X402964D03*
X405479D03*
X400038D03*
X393357Y211066D03*
X403857D03*
X394450Y217359D03*
Y214106D03*
X396950Y217359D03*
X399450Y217344D03*
X402450Y217359D03*
X404950D03*
X402450Y214106D03*
X404950D03*
X394450Y415631D03*
Y412378D03*
X396950Y415631D03*
X399450Y415616D03*
X393357Y409338D03*
X402450Y415631D03*
X404950D03*
X402450Y412378D03*
X404950D03*
X403857Y409338D03*
X414143Y211066D03*
X415550Y214106D03*
Y217359D03*
X413050D03*
Y214106D03*
X410550Y217359D03*
X408050Y217344D03*
X415550Y412378D03*
Y415631D03*
X413050D03*
Y412378D03*
X410550Y415631D03*
X408050Y415616D03*
X414143Y409338D03*
G54D22*
X23723Y123791D03*
Y120791D03*
X32223Y123791D03*
Y120791D03*
X40723Y123791D03*
Y120791D03*
X49223Y123791D03*
Y121291D03*
X38300Y109200D03*
X60411Y130200D03*
X57470Y426544D03*
X51535D03*
X56482Y450344D03*
X62600Y450700D03*
X71035Y426543D03*
X76770D03*
X142780Y266830D03*
X142500Y345800D03*
X175359Y153286D03*
X178346Y162898D03*
Y172347D03*
Y184945D03*
X181194Y294074D03*
X169669Y399419D03*
X197243Y156599D03*
X187794Y159748D03*
X197243Y178646D03*
X187794Y181795D03*
X197243Y191244D03*
Y197506D03*
Y203805D03*
X184645Y206955D03*
X197243Y200655D03*
Y219553D03*
X194094Y232151D03*
X184645D03*
X185725Y307320D03*
X209842Y156599D03*
X203542Y169197D03*
X212991D03*
X206692D03*
X212991Y181795D03*
X206692Y178646D03*
X209842Y181795D03*
X203542Y191244D03*
X206692D03*
X209842Y184945D03*
X200393Y191244D03*
X203542Y197506D03*
X209842D03*
X203542Y210104D03*
X212991Y206955D03*
Y210104D03*
X209842D03*
X200393D03*
X203542Y200655D03*
X209842D03*
X212991Y219553D03*
X205130Y282000D03*
X204207Y278200D03*
X225552Y156599D03*
X219253Y178646D03*
X225552D03*
Y184945D03*
X219253Y232151D03*
X215600Y316800D03*
X228702Y169197D03*
X231851Y191244D03*
X241300D03*
X235001Y184945D03*
X228702Y191244D03*
X235001Y200655D03*
Y206955D03*
Y219553D03*
X241300Y213254D03*
X238150Y219553D03*
X228702D03*
X238630Y235654D03*
X231851Y232151D03*
X241300D03*
X255492Y152905D03*
X244450Y156599D03*
X253898Y172347D03*
Y178646D03*
X247599Y181795D03*
Y175496D03*
X253898Y191244D03*
Y184945D03*
X247599Y197506D03*
Y188095D03*
Y203805D03*
X253898Y206955D03*
Y200655D03*
X257048Y219553D03*
X250749D03*
Y232151D03*
X257048Y235301D03*
X263294Y153366D03*
X263030Y150846D03*
X268391Y207262D03*
X269391Y214593D03*
X280744Y142070D03*
X283248Y142046D03*
X287725Y363473D03*
X293693Y152232D03*
X290889Y152318D03*
X297372Y196616D03*
X308500Y382100D03*
X339800Y154911D03*
Y159911D03*
Y165911D03*
Y169911D03*
Y176911D03*
Y179911D03*
Y185911D03*
Y189911D03*
X337004Y202113D03*
Y206113D03*
Y210113D03*
G54D37*
X262880Y178977D03*
X308460Y214178D03*
G54D41*
X441000Y-454000D03*
X451000D03*
X441000Y-333400D03*
X451000D03*
X441000Y2000D03*
X451000D03*
X441000Y116000D03*
X451000D03*
G54D15*
X17716Y18465D03*
X45276D03*
X264173Y20040D03*
X291733D03*
X309055Y18465D03*
X336615D03*
G54D31*
X143118Y44803D03*
X194851D03*
G54D32*
X153237Y58583D03*
X165048Y52677D03*
X155205D03*
X161111Y58583D03*
X168985D03*
X172922Y52677D03*
X176859Y58583D03*
X184733D03*
G54D40*
X441000Y-444000D03*
X451000D03*
Y-355000D03*
X441000D03*
Y-323400D03*
X451000D03*
Y-245000D03*
X441000D03*
X451000Y-215000D03*
X441000D03*
Y-136600D03*
X451000D03*
Y-107000D03*
X441000D03*
Y-18000D03*
X451000D03*
X441000Y12000D03*
X451000D03*
Y96000D03*
X441000D03*
Y126000D03*
X451000D03*
Y200000D03*
X441000D03*
X451000Y230000D03*
X441000D03*
Y304000D03*
X451000D03*
Y336000D03*
X441000D03*
Y420000D03*
X451000D03*
G54D44*
X441000Y-126600D03*
X451000D03*
X441000Y-8000D03*
X451000D03*
X441000Y314000D03*
X451000D03*
X441000Y430000D03*
X451000D03*
G54D18*
X24016Y89331D03*
X330315D03*
G54D11*
X-61709Y56192D03*
X-51709D03*
X-61100Y250316D03*
X-61000Y382816D03*
X-51100Y250316D03*
X-51000Y382816D03*
X-35000Y56184D03*
X-25000D03*
X-25100Y250316D03*
X-35100D03*
X-36000Y418816D03*
X-26000D03*
G54D26*
X65945Y297776D03*
G54D36*
X236220Y424016D03*
X301181D03*
G54D33*
X144685Y297776D03*
G54D17*
X22047Y46417D03*
X333466D03*
G54D30*
X105316Y213343D03*
G54D24*
X23819Y349154D03*
X95709Y52244D03*
G54D34*
X182764Y52677D03*
G54D35*
X221142Y24764D03*
G54D10*
X-56709Y43008D03*
X-30000Y43000D03*
G54D29*
X105315Y186571D03*
G54D21*
X27300Y68200D03*
X340639Y432809D03*
G54D20*
X18000Y240900D03*
Y237900D03*
Y249900D03*
Y246900D03*
Y243900D03*
X15688Y259063D03*
X21135Y236587D03*
X21205Y232767D03*
X21135Y240667D03*
Y243737D03*
X24690Y246467D03*
Y251967D03*
X21135Y246837D03*
X21035Y249937D03*
X24690Y249267D03*
X22237Y311481D03*
Y308592D03*
X30638Y311957D03*
Y309068D03*
X22692Y466518D03*
X47440Y308691D03*
X39039Y309044D03*
Y311933D03*
X47440Y312080D03*
X63300Y237600D03*
X68375Y144100D03*
X70580Y167179D03*
X65800Y260875D03*
X81600Y241500D03*
X87500Y237300D03*
X84000Y261375D03*
X103500Y240619D03*
X113590Y245170D03*
X143300Y396400D03*
X146600Y410600D03*
X172550Y398690D03*
X200274Y410960D03*
X225552Y197543D03*
X225441Y282267D03*
X257048Y225890D03*
X292361Y197970D03*
X314985Y397639D03*
Y394639D03*
X332470Y397092D03*
Y394092D03*
X331646Y466536D03*
X339101Y117328D03*
Y121128D03*
X337842Y128533D03*
X334723Y226349D03*
Y229738D03*
X351331Y20788D03*
Y40788D03*
Y60788D03*
Y80788D03*
Y100788D03*
Y120788D03*
Y140788D03*
Y160788D03*
Y180788D03*
Y200788D03*
Y220788D03*
Y240788D03*
Y260788D03*
Y280788D03*
Y300788D03*
Y357531D03*
Y377531D03*
Y397531D03*
Y417531D03*
Y437531D03*
X373420Y-447134D03*
X370905D03*
Y-443881D03*
X373420D03*
X376346Y-447134D03*
X372211Y-440841D03*
X372183Y-162569D03*
X373392Y-168862D03*
X370877D03*
Y-165609D03*
X373392D03*
X376318Y-168862D03*
X373420Y59410D03*
X370905D03*
Y62663D03*
X373420D03*
X376346Y59410D03*
X372211Y65703D03*
X391993Y-473196D03*
Y-469943D03*
X381788Y-443881D03*
X384303D03*
Y-447134D03*
X378862Y-447119D03*
X381788Y-447134D03*
X382997Y-440841D03*
X381760Y-165609D03*
X384275D03*
Y-168862D03*
X378834Y-168847D03*
X381760Y-168862D03*
X382969Y-162569D03*
X391950Y-74043D03*
Y-70790D03*
X381788Y62663D03*
X384303D03*
Y59410D03*
X378862Y59425D03*
X381788Y59410D03*
X382997Y65703D03*
X391950Y255229D03*
Y258482D03*
X405391Y-473196D03*
X399950Y-473181D03*
X402876Y-473196D03*
X394508D03*
X397434D03*
X402876Y-469943D03*
X405391D03*
X404085Y-466903D03*
X393299D03*
X394508Y-469943D03*
X399450Y-74028D03*
X394450Y-74043D03*
Y-70790D03*
X396950Y-74043D03*
X405050D03*
X402550D03*
X405050Y-70790D03*
X402550D03*
X393357Y-67750D03*
X403643D03*
X394450Y255229D03*
X396950D03*
X399450Y255244D03*
X405050Y255229D03*
X402550D03*
X394450Y258482D03*
X393357Y261522D03*
X405050Y258482D03*
X402550D03*
X403643Y261522D03*
X415550Y-70790D03*
Y-74043D03*
X413050D03*
Y-70790D03*
X410550Y-74043D03*
X408050Y-74028D03*
X414143Y-67750D03*
X415550Y255229D03*
X413050D03*
X410550D03*
X408050Y255244D03*
X415550Y258482D03*
X413050D03*
X414143Y261522D03*
G54D38*
X285482Y190187D03*
G54D16*
X9407Y10554D03*
X12900Y105500D03*
X17000Y211541D03*
Y215713D03*
Y219288D03*
X8300Y314700D03*
X22218Y3000D03*
X27323Y25842D03*
X31920Y186610D03*
X25811Y319400D03*
X32000Y326300D03*
X23535Y329990D03*
X34300Y375000D03*
X33100Y392100D03*
X20225Y447671D03*
X42218Y3000D03*
X35044Y35751D03*
X43926Y62248D03*
X45276Y98488D03*
X47294Y184491D03*
X39567Y243133D03*
X40500Y236900D03*
X41574Y255937D03*
X44500Y355500D03*
X38200Y364855D03*
X36600Y408600D03*
X40848Y448440D03*
X62218Y3000D03*
X53000Y41500D03*
X59425Y53075D03*
X50508Y57459D03*
X57500Y75500D03*
X60000D03*
X53267Y109094D03*
X57141Y209341D03*
X59900Y199900D03*
X52000Y230400D03*
X62500Y272500D03*
X60561Y314843D03*
X62458Y390481D03*
X59097Y433502D03*
X63563Y460100D03*
X56476D03*
X76500Y66500D03*
X65928Y76500D03*
X72044Y132312D03*
X71970Y135893D03*
X69195Y135799D03*
X69285Y132321D03*
X67126Y128100D03*
X68335Y141369D03*
X68434Y149506D03*
X68432Y152147D03*
X65301Y187762D03*
X67486Y186414D03*
X72000Y235925D03*
X65801Y253145D03*
X76500Y270700D03*
X74000Y270800D03*
X76284Y280470D03*
X75300Y305150D03*
X69500Y308700D03*
X64567Y306665D03*
X73000Y323400D03*
X68757Y352724D03*
X71906Y355873D03*
X75056Y359023D03*
X65607Y349574D03*
X75056Y377883D03*
X68757Y384182D03*
X65607Y387332D03*
X75018Y381033D03*
X69057Y419700D03*
X78800Y423800D03*
X66297Y433002D03*
X70650Y460100D03*
X77500D03*
X82218Y3000D03*
X91700Y66500D03*
X86500Y75000D03*
X88500Y128000D03*
X81800Y188500D03*
X90900Y222850D03*
X85672Y283985D03*
X81864Y297900D03*
X85600Y298100D03*
X82200Y308700D03*
X82022Y303350D03*
X84126Y311790D03*
X79600Y312000D03*
X85500Y323400D03*
X85600Y335000D03*
X87617Y365322D03*
Y371584D03*
X81355Y365322D03*
Y371584D03*
X86300Y397600D03*
X92001Y450402D03*
X82256Y445577D03*
X85276Y445550D03*
X84823Y460100D03*
X91909Y458275D03*
X102218Y3000D03*
X95400Y66500D03*
X98000Y75500D03*
X108727Y99153D03*
X100000Y98500D03*
X105916Y109952D03*
X101230Y127010D03*
X96400Y137475D03*
X97440Y283590D03*
X105000Y311900D03*
X96457Y323194D03*
X97608Y335534D03*
X100215Y352724D03*
X103383Y349556D03*
X93916Y359023D03*
X97066Y355873D03*
X103383Y387350D03*
X100215Y384182D03*
X93916Y377883D03*
X97066Y381033D03*
X103400Y420000D03*
X95280Y412500D03*
X97156Y450437D03*
X94560Y443287D03*
X100225Y443127D03*
X98996Y458275D03*
X106083D03*
X122218Y3000D03*
X111000Y44600D03*
X122500Y58000D03*
X116560Y88651D03*
X120726Y105000D03*
X115200Y98200D03*
X120626Y123500D03*
X112000D03*
X116200Y115100D03*
X119060Y199695D03*
X118300Y237500D03*
X121720Y265330D03*
X111177Y293471D03*
X118009Y313810D03*
Y311200D03*
X115000Y369500D03*
X127900Y45000D03*
X129575Y57375D03*
X129328Y122500D03*
X126575Y111416D03*
X131700Y131000D03*
X133500Y149385D03*
X124500Y167100D03*
X126300Y176575D03*
X135000Y206900D03*
X128900Y255898D03*
X131216Y280187D03*
X124016Y313784D03*
X135462Y313727D03*
X133100Y358900D03*
X133640Y390524D03*
X124287Y406262D03*
X127300Y392600D03*
X129900Y415583D03*
X138500Y457250D03*
X142218Y3000D03*
X147947Y9800D03*
X146800Y79000D03*
X140869Y89055D03*
X141700Y96929D03*
X140869Y104803D03*
Y120551D03*
Y112677D03*
X142000Y146000D03*
X148400Y155765D03*
X153134Y178572D03*
X146390Y224040D03*
X146000Y216350D03*
X141954Y224274D03*
X142300Y216300D03*
X152400Y293400D03*
X150293Y315493D03*
X140700Y370252D03*
X140300Y395100D03*
X152100Y425700D03*
X145365Y426050D03*
X149041Y458750D03*
X162218Y3000D03*
X165700Y11100D03*
X166719Y75874D03*
X168297Y93976D03*
X164429Y93991D03*
X158873Y93976D03*
X166500Y96400D03*
X158420Y116610D03*
X159700Y112000D03*
X161237Y185815D03*
X161240Y190477D03*
X166361Y209794D03*
X166308Y225189D03*
X155800Y234700D03*
X163690Y268610D03*
X164790Y341100D03*
X163800Y356800D03*
X164318Y389102D03*
X157282D03*
X156900Y385700D03*
X154000Y414750D03*
X165194Y428688D03*
X160852Y460118D03*
X182218Y3000D03*
X173853Y93991D03*
X182925Y84300D03*
X180333Y114292D03*
X178346Y200655D03*
Y213254D03*
Y225852D03*
X174079Y234604D03*
X174400Y249136D03*
X173880Y312430D03*
X182372Y325961D03*
X169200Y349400D03*
X180350Y368650D03*
X177082Y387402D03*
X182750Y426750D03*
X187272Y84472D03*
X191312Y84512D03*
X190200Y100500D03*
X198281Y101286D03*
X187360Y132425D03*
X187794Y213254D03*
X196827Y240349D03*
X185897Y249936D03*
X191583Y261363D03*
X189228Y280655D03*
X190922Y350990D03*
X184118Y387402D03*
X185875Y415051D03*
X189600Y459800D03*
X202218Y3000D03*
X207700Y59100D03*
X213100Y69300D03*
X209500Y92326D03*
X211800Y93870D03*
X209824Y106122D03*
X203600Y117000D03*
X203970Y125500D03*
X211200Y140513D03*
X200393Y169197D03*
X203542Y232151D03*
X198990Y247811D03*
X211265Y267300D03*
X207220Y301180D03*
X207750Y366500D03*
X208360Y384890D03*
X203180Y416371D03*
X211865Y444520D03*
X200000Y455800D03*
X209300Y457700D03*
X222218Y3000D03*
X227547Y74275D03*
X219600Y74000D03*
X215800Y69300D03*
X218600D03*
X224958Y107236D03*
X221500Y125100D03*
X217697Y174852D03*
X219290Y191207D03*
X222402Y206955D03*
Y213254D03*
X223672Y290735D03*
X213610Y308800D03*
X223160Y362600D03*
X222225Y407650D03*
X216725D03*
X218085Y444520D03*
X222200Y458700D03*
X215000Y458600D03*
X242218Y3000D03*
X233000Y47100D03*
X230800Y57613D03*
X239347Y79457D03*
X237280Y107510D03*
X229000Y101000D03*
X242812Y117501D03*
X242800Y132200D03*
X231100Y125600D03*
X235001Y166047D03*
X238150Y169197D03*
X232773Y269532D03*
X228800Y302700D03*
X241400Y328100D03*
X233468Y341046D03*
X233300Y356890D03*
X233600Y371500D03*
X233800Y390118D03*
X228230Y390390D03*
X228200Y459100D03*
X248359Y46559D03*
X248700Y75900D03*
X255750Y77350D03*
X250900Y90900D03*
X254397Y103697D03*
X244987Y103528D03*
X251113Y102919D03*
X252300Y107664D03*
X245391Y99589D03*
X252374Y132159D03*
X244450Y159748D03*
X253388Y273655D03*
X246200Y299700D03*
X243410Y381323D03*
X245300Y445800D03*
X262218Y3000D03*
X267022Y12166D03*
X269095Y34625D03*
X260970Y42441D03*
X268675Y74400D03*
X267168Y93768D03*
X260132D03*
X259759Y103651D03*
X259500Y101100D03*
X268435Y121476D03*
X260269Y207358D03*
X261269Y214657D03*
X266200Y300500D03*
X262930Y325300D03*
X259420Y345930D03*
X265922Y354238D03*
X272100Y396300D03*
X265100Y424000D03*
X266300Y435900D03*
X271500Y446800D03*
X269534Y459061D03*
X282218Y3000D03*
X277000Y41982D03*
X282440Y51941D03*
X274219Y51641D03*
X286000Y67975D03*
X274400Y90019D03*
X279200Y114100D03*
X274500Y131629D03*
X279600Y131400D03*
X285980Y163487D03*
X278155Y176085D03*
X286105Y172936D03*
Y182385D03*
Y197989D03*
Y201139D03*
X286000Y242100D03*
X281889Y287636D03*
X276155Y329999D03*
X276100Y375900D03*
Y381500D03*
X284614Y387136D03*
X281300Y419300D03*
X278200Y408700D03*
X277563Y460028D03*
X283707Y459398D03*
X302218Y3000D03*
X300600Y10591D03*
X288856Y12166D03*
X295402Y48051D03*
X290245Y46978D03*
X300856Y104059D03*
X301151Y108649D03*
X301936Y135797D03*
X294200Y128800D03*
X301507Y195435D03*
X289091Y204331D03*
X289254Y210587D03*
Y213737D03*
X301500Y326500D03*
X298748Y390118D03*
X297399Y397382D03*
X290800Y438300D03*
X291689Y453912D03*
Y456912D03*
Y459912D03*
X313977Y33400D03*
X303575Y54516D03*
X304436Y135897D03*
X307500Y125635D03*
X308008Y163487D03*
X311158Y185534D03*
X314307Y191690D03*
X311158Y194839D03*
Y204288D03*
X314307Y207438D03*
X303940Y212664D03*
X311158Y201139D03*
Y213737D03*
X307500Y256500D03*
X312114Y288439D03*
X315810Y293450D03*
X312315Y293207D03*
X317430Y295665D03*
X314820Y296128D03*
X314201Y302361D03*
X314180Y299440D03*
X303077Y297519D03*
X314132Y310178D03*
X314170Y307020D03*
X309500Y315000D03*
X304000Y305000D03*
X311000Y320500D03*
X315075Y366500D03*
X312226Y382766D03*
X322218Y3000D03*
X319175Y60200D03*
X322600Y76100D03*
X331881Y108593D03*
Y104577D03*
Y112608D03*
X320239Y151075D03*
X323384Y157378D03*
X331405Y157411D03*
X323384Y165378D03*
Y161378D03*
Y169378D03*
Y173378D03*
Y177378D03*
X331405Y177411D03*
Y187411D03*
Y192411D03*
X319601Y201140D03*
X317670Y291430D03*
X330900Y314700D03*
X325038Y356890D03*
X325320Y390118D03*
X325200Y383900D03*
X342218Y3000D03*
X337375Y76600D03*
X342900Y66100D03*
X333278Y151129D03*
X337083Y197000D03*
X336312Y286352D03*
X339700Y295900D03*
X342604Y318773D03*
X335700Y376400D03*
X335500Y363200D03*
X334600Y383300D03*
X334112Y447668D03*
X349290Y337646D03*
X374975Y-435380D03*
X374666Y-218571D03*
X374947Y-157108D03*
X374666Y9701D03*
X374975Y71164D03*
X374666Y378973D03*
X380602Y-435533D03*
X380293Y-218724D03*
X380574Y-157261D03*
X380293Y9548D03*
X380602Y71011D03*
X380293Y378820D03*
X396063Y-461442D03*
X401690Y-461595D03*
X401409Y-123786D03*
X395782Y-123633D03*
G54D42*
X451000Y-345000D03*
X441000D03*
X451000Y-235000D03*
X441000D03*
X451000Y106000D03*
X441000D03*
X451000Y210000D03*
X441000D03*
G54D43*
X451000Y-225000D03*
X441000D03*
X451000Y-117000D03*
X441000D03*
X451000Y220000D03*
X441000D03*
X451000Y326000D03*
X441000D03*
G54D27*
X58654Y290605D03*
X104575Y62369D03*
Y67581D03*
G54D13*
X-30100Y263500D03*
G54D12*
X-56100D03*
X-56000Y396000D03*
X-31000Y432000D03*
%LPC*%
G75*
G54D45*
G01X2010999Y-388000D02*
Y1475775D01*
X-407000D01*
Y-386798D01*
Y-755294D01*
Y-793716D01*
X-368578D01*
X1942346D01*
X2010999D01*
Y-725063D01*
Y-388000D01*
G01X-53307Y-609436D02*
Y-684436D01*
X446693D01*
Y-609436D01*
X-53307D01*
G01X-41307Y-674436D02*
Y-679436D01*
G01X-42764Y-674436D02*
X-39850D01*
G01X-34940Y-679436D02*
X-37474D01*
Y-674436D01*
X-34940D01*
G01X-35954Y-676853D02*
X-37474D01*
G01X-32374Y-674436D02*
Y-679436D01*
X-29840D01*
G01X-26007Y-679603D02*
X-26134Y-679519D01*
Y-679353D01*
X-26007Y-679269D01*
X-25880Y-679353D01*
Y-679519D01*
X-26007Y-679603D01*
G01Y-677353D02*
X-26134Y-677269D01*
Y-677103D01*
X-26007Y-677019D01*
X-25880Y-677103D01*
Y-677269D01*
X-26007Y-677353D01*
G01X-21224Y-681103D02*
X-21857Y-680269D01*
X-22174Y-679436D01*
Y-676103D01*
X-21857Y-675269D01*
X-21224Y-674436D01*
G01X-15807D02*
X-16314Y-674603D01*
X-16694Y-675019D01*
X-16947Y-675519D01*
X-17137Y-676186D01*
X-17200Y-676936D01*
X-17137Y-677686D01*
X-16947Y-678353D01*
X-16694Y-678853D01*
X-16314Y-679269D01*
X-15807Y-679436D01*
X-15300Y-679269D01*
X-14920Y-678853D01*
X-14667Y-678353D01*
X-14477Y-677686D01*
X-14414Y-676936D01*
X-14477Y-676186D01*
X-14667Y-675519D01*
X-14920Y-675019D01*
X-15300Y-674603D01*
X-15807Y-674436D01*
G01X-12100Y-678436D02*
X-11720Y-679019D01*
X-11214Y-679353D01*
X-10644Y-679436D01*
X-10137Y-679353D01*
X-9630Y-678936D01*
X-9314Y-678436D01*
X-9250Y-677936D01*
X-9377Y-677353D01*
X-9820Y-676936D01*
X-10264Y-676769D01*
X-10834D01*
G01X-10264D02*
X-9884Y-676519D01*
X-9567Y-676103D01*
X-9440Y-675603D01*
X-9567Y-675103D01*
X-9884Y-674686D01*
X-10454Y-674436D01*
X-11024Y-674519D01*
X-11594Y-674853D01*
G01X-5290Y-681103D02*
X-4657Y-680269D01*
X-4340Y-679436D01*
Y-676103D01*
X-4657Y-675269D01*
X-5290Y-674436D01*
G01X-1900Y-678436D02*
X-1520Y-679019D01*
X-1014Y-679353D01*
X-444Y-679436D01*
X63Y-679353D01*
X570Y-678936D01*
X886Y-678436D01*
X950Y-677936D01*
X823Y-677353D01*
X380Y-676936D01*
X-64Y-676769D01*
X-634D01*
G01X-64D02*
X316Y-676519D01*
X633Y-676103D01*
X760Y-675603D01*
X633Y-675103D01*
X316Y-674686D01*
X-254Y-674436D01*
X-824Y-674519D01*
X-1394Y-674853D01*
G01X3390Y-675269D02*
X3770Y-674769D01*
X4213Y-674519D01*
X4720Y-674436D01*
X5353Y-674603D01*
X5796Y-675019D01*
X5923Y-675519D01*
X5860Y-676019D01*
X5606Y-676436D01*
X4340Y-677269D01*
X3770Y-677853D01*
X3390Y-678686D01*
X3263Y-679436D01*
X5923D01*
G01X9566D02*
X9693Y-678353D01*
X9883Y-677436D01*
X10136Y-676603D01*
X10453Y-675686D01*
X10960Y-674436D01*
X8426D01*
G01X13970Y-677769D02*
X15616D01*
G01X18690Y-675269D02*
X19070Y-674769D01*
X19513Y-674519D01*
X20020Y-674436D01*
X20653Y-674603D01*
X21096Y-675019D01*
X21223Y-675519D01*
X21160Y-676019D01*
X20906Y-676436D01*
X19640Y-677269D01*
X19070Y-677853D01*
X18690Y-678686D01*
X18563Y-679436D01*
X21223D01*
G01X23600Y-678436D02*
X23980Y-679019D01*
X24486Y-679353D01*
X25056Y-679436D01*
X25563Y-679353D01*
X26070Y-678936D01*
X26386Y-678436D01*
X26450Y-677936D01*
X26323Y-677353D01*
X25880Y-676936D01*
X25436Y-676769D01*
X24866D01*
G01X25436D02*
X25816Y-676519D01*
X26133Y-676103D01*
X26260Y-675603D01*
X26133Y-675103D01*
X25816Y-674686D01*
X25246Y-674436D01*
X24676Y-674519D01*
X24106Y-674853D01*
G01X30853Y-679436D02*
Y-674436D01*
X28510Y-678019D01*
X31676D01*
G01X33800Y-678686D02*
X34180Y-679103D01*
X34623Y-679353D01*
X35193Y-679436D01*
X35763Y-679269D01*
X36206Y-678936D01*
X36523Y-678353D01*
X36586Y-677686D01*
X36460Y-677019D01*
X36143Y-676603D01*
X35700Y-676269D01*
X35256Y-676186D01*
X34813Y-676269D01*
X34243Y-676603D01*
X34433Y-674436D01*
X36143D01*
G01X44190Y-679436D02*
Y-674436D01*
X46596D01*
G01X45710Y-676853D02*
X44190D01*
G01X48910Y-679436D02*
X50493Y-674436D01*
X52076Y-679436D01*
G01X51506Y-677686D02*
X49480D01*
G01X54263Y-679436D02*
X56923Y-674436D01*
G01X54263D02*
X56923Y-679436D01*
G01X60693Y-679603D02*
X60566Y-679519D01*
Y-679353D01*
X60693Y-679269D01*
X60820Y-679353D01*
Y-679519D01*
X60693Y-679603D01*
G01Y-677353D02*
X60566Y-677269D01*
Y-677103D01*
X60693Y-677019D01*
X60820Y-677103D01*
Y-677269D01*
X60693Y-677353D01*
G01X65476Y-681103D02*
X64843Y-680269D01*
X64526Y-679436D01*
Y-676103D01*
X64843Y-675269D01*
X65476Y-674436D01*
G01X70893D02*
X70386Y-674603D01*
X70006Y-675019D01*
X69753Y-675519D01*
X69563Y-676186D01*
X69500Y-676936D01*
X69563Y-677686D01*
X69753Y-678353D01*
X70006Y-678853D01*
X70386Y-679269D01*
X70893Y-679436D01*
X71400Y-679269D01*
X71780Y-678853D01*
X72033Y-678353D01*
X72223Y-677686D01*
X72286Y-676936D01*
X72223Y-676186D01*
X72033Y-675519D01*
X71780Y-675019D01*
X71400Y-674603D01*
X70893Y-674436D01*
G01X74600Y-678436D02*
X74980Y-679019D01*
X75486Y-679353D01*
X76056Y-679436D01*
X76563Y-679353D01*
X77070Y-678936D01*
X77386Y-678436D01*
X77450Y-677936D01*
X77323Y-677353D01*
X76880Y-676936D01*
X76436Y-676769D01*
X75866D01*
G01X76436D02*
X76816Y-676519D01*
X77133Y-676103D01*
X77260Y-675603D01*
X77133Y-675103D01*
X76816Y-674686D01*
X76246Y-674436D01*
X75676Y-674519D01*
X75106Y-674853D01*
G01X81410Y-681103D02*
X82043Y-680269D01*
X82360Y-679436D01*
Y-676103D01*
X82043Y-675269D01*
X81410Y-674436D01*
G01X84800Y-678436D02*
X85180Y-679019D01*
X85686Y-679353D01*
X86256Y-679436D01*
X86763Y-679353D01*
X87270Y-678936D01*
X87586Y-678436D01*
X87650Y-677936D01*
X87523Y-677353D01*
X87080Y-676936D01*
X86636Y-676769D01*
X86066D01*
G01X86636D02*
X87016Y-676519D01*
X87333Y-676103D01*
X87460Y-675603D01*
X87333Y-675103D01*
X87016Y-674686D01*
X86446Y-674436D01*
X85876Y-674519D01*
X85306Y-674853D01*
G01X90216Y-678853D02*
X90660Y-679269D01*
X91166Y-679436D01*
X91673Y-679269D01*
X92116Y-678769D01*
X92433Y-678019D01*
X92560Y-677269D01*
Y-676353D01*
X92433Y-675603D01*
X92116Y-674936D01*
X91736Y-674603D01*
X91293Y-674436D01*
X90786Y-674603D01*
X90406Y-674936D01*
X90153Y-675436D01*
X90026Y-676103D01*
X90153Y-676686D01*
X90470Y-677269D01*
X90850Y-677603D01*
X91293Y-677686D01*
X91800Y-677519D01*
X92180Y-677103D01*
X92560Y-676353D01*
G01X96266Y-679436D02*
X96393Y-678353D01*
X96583Y-677436D01*
X96836Y-676603D01*
X97153Y-675686D01*
X97660Y-674436D01*
X95126D01*
G01X100670Y-677769D02*
X102316D01*
G01X105200Y-678436D02*
X105580Y-679019D01*
X106086Y-679353D01*
X106656Y-679436D01*
X107163Y-679353D01*
X107670Y-678936D01*
X107986Y-678436D01*
X108050Y-677936D01*
X107923Y-677353D01*
X107480Y-676936D01*
X107036Y-676769D01*
X106466D01*
G01X107036D02*
X107416Y-676519D01*
X107733Y-676103D01*
X107860Y-675603D01*
X107733Y-675103D01*
X107416Y-674686D01*
X106846Y-674436D01*
X106276Y-674519D01*
X105706Y-674853D01*
G01X110490Y-677353D02*
X110933Y-676769D01*
X111313Y-676436D01*
X111820Y-676269D01*
X112263Y-676436D01*
X112580Y-676769D01*
X112833Y-677269D01*
X112896Y-677853D01*
X112833Y-678353D01*
X112580Y-678853D01*
X112200Y-679269D01*
X111756Y-679436D01*
X111250Y-679269D01*
X110806Y-678769D01*
X110553Y-678019D01*
X110490Y-677186D01*
X110616Y-676103D01*
X110806Y-675519D01*
X111123Y-674936D01*
X111566Y-674519D01*
X112010Y-674436D01*
X112453Y-674603D01*
X112770Y-675019D01*
G01X116793Y-679436D02*
Y-674436D01*
X116033Y-675436D01*
G01Y-679436D02*
X117553D01*
G01X122653D02*
Y-674436D01*
X120310Y-678019D01*
X123476D01*
G01X141693Y-609436D02*
Y-684436D01*
G01Y-659436D02*
X244693D01*
Y-634436D01*
G01X141693D02*
X244693D01*
G01X246693Y-609436D02*
Y-684436D01*
G01X244693Y-609436D02*
Y-684436D01*
G01X252200Y-669436D02*
Y-664436D01*
X253466D01*
X253973Y-664686D01*
X254353Y-665019D01*
X254670Y-665519D01*
X254923Y-666103D01*
X254986Y-666936D01*
X254923Y-667769D01*
X254670Y-668353D01*
X254353Y-668853D01*
X253973Y-669186D01*
X253466Y-669436D01*
X252200D01*
G01X257110D02*
X258693Y-664436D01*
X260276Y-669436D01*
G01X259706Y-667686D02*
X257680D01*
G01X263793Y-664436D02*
Y-669436D01*
G01X262336Y-664436D02*
X265250D01*
G01X270160Y-669436D02*
X267626D01*
Y-664436D01*
X270160D01*
G01X269146Y-666853D02*
X267626D01*
G01X273993Y-669603D02*
X273866Y-669519D01*
Y-669353D01*
X273993Y-669269D01*
X274120Y-669353D01*
Y-669519D01*
X273993Y-669603D01*
G01Y-667353D02*
X273866Y-667269D01*
Y-667103D01*
X273993Y-667019D01*
X274120Y-667103D01*
Y-667269D01*
X273993Y-667353D01*
G01X246693Y-659436D02*
X446693D01*
G01X252326Y-644436D02*
Y-639436D01*
X253846D01*
X254353Y-639686D01*
X254733Y-640269D01*
X254860Y-640936D01*
X254733Y-641603D01*
X254416Y-642103D01*
X253846Y-642353D01*
X252326D01*
G01X257553Y-644603D02*
X259833Y-639436D01*
G01X262336Y-644436D02*
Y-639436D01*
X265250Y-644436D01*
Y-639436D01*
G01X268893Y-644603D02*
X268766Y-644519D01*
Y-644353D01*
X268893Y-644269D01*
X269020Y-644353D01*
Y-644519D01*
X268893Y-644603D01*
G01Y-642353D02*
X268766Y-642269D01*
Y-642103D01*
X268893Y-642019D01*
X269020Y-642103D01*
Y-642269D01*
X268893Y-642353D01*
G01X246693Y-634436D02*
X446693D01*
G01X252326Y-619436D02*
Y-614436D01*
X253846D01*
X254353Y-614686D01*
X254733Y-615269D01*
X254860Y-615936D01*
X254733Y-616603D01*
X254416Y-617103D01*
X253846Y-617353D01*
X252326D01*
G01X257426Y-619436D02*
Y-614436D01*
X259010D01*
X259516Y-614686D01*
X259833Y-615019D01*
X259960Y-615686D01*
X259833Y-616353D01*
X259453Y-616769D01*
X259010Y-617019D01*
X257426D01*
G01X259010D02*
X259960Y-619436D01*
G01X263793D02*
X263286Y-619353D01*
X262843Y-619019D01*
X262463Y-618519D01*
X262210Y-617936D01*
X262083Y-617269D01*
Y-616603D01*
X262210Y-615936D01*
X262463Y-615353D01*
X262843Y-614853D01*
X263286Y-614519D01*
X263793Y-614436D01*
X264300Y-614519D01*
X264743Y-614853D01*
X265123Y-615353D01*
X265376Y-615936D01*
X265503Y-616603D01*
Y-617269D01*
X265376Y-617936D01*
X265123Y-618519D01*
X264743Y-619019D01*
X264300Y-619353D01*
X263793Y-619436D01*
G01X267626Y-618436D02*
X267943Y-618936D01*
X268323Y-619269D01*
X268766Y-619436D01*
X269273Y-619269D01*
X269653Y-618936D01*
X270033Y-618436D01*
X270160Y-617769D01*
Y-614436D01*
G01X275260Y-619436D02*
X272726D01*
Y-614436D01*
X275260D01*
G01X274246Y-616853D02*
X272726D01*
G01X280486Y-614853D02*
X280106Y-614603D01*
X279663Y-614436D01*
X279156D01*
X278586Y-614686D01*
X278143Y-615103D01*
X277826Y-615603D01*
X277573Y-616436D01*
X277510Y-617186D01*
X277636Y-617936D01*
X277826Y-618436D01*
X278206Y-618936D01*
X278650Y-619269D01*
X279093Y-619436D01*
X279536D01*
X279980Y-619269D01*
X280360Y-619019D01*
X280676Y-618686D01*
G01X284193Y-614436D02*
Y-619436D01*
G01X282736Y-614436D02*
X285650D01*
G01X289293Y-619603D02*
X289166Y-619519D01*
Y-619353D01*
X289293Y-619269D01*
X289420Y-619353D01*
Y-619519D01*
X289293Y-619603D01*
G01Y-617353D02*
X289166Y-617269D01*
Y-617103D01*
X289293Y-617019D01*
X289420Y-617103D01*
Y-617269D01*
X289293Y-617353D01*
G01X361693Y-659436D02*
Y-684436D01*
G01X364326Y-661936D02*
Y-666936D01*
X366860D01*
G01X369933Y-661936D02*
X371453D01*
G01X370693D02*
Y-666936D01*
G01X369933D02*
X371453D01*
G01X376300Y-664269D02*
X376553Y-664019D01*
X376743Y-663603D01*
X376870Y-663019D01*
X376743Y-662519D01*
X376490Y-662186D01*
X376046Y-661936D01*
X374336D01*
Y-666936D01*
X376426D01*
X376870Y-666603D01*
X377123Y-666103D01*
X377250Y-665519D01*
X377123Y-664936D01*
X376743Y-664436D01*
X376300Y-664269D01*
X374336D01*
G01X380893Y-667103D02*
X380766Y-667019D01*
Y-666853D01*
X380893Y-666769D01*
X381020Y-666853D01*
Y-667019D01*
X380893Y-667103D01*
G01Y-664853D02*
X380766Y-664769D01*
Y-664603D01*
X380893Y-664519D01*
X381020Y-664603D01*
Y-664769D01*
X380893Y-664853D01*
G01X404693Y-659436D02*
Y-684436D01*
G01Y-634436D02*
Y-659436D01*
G01X412706Y-687603D02*
X412813Y-687478D01*
X412893Y-687269D01*
X412946Y-686978D01*
X412893Y-686728D01*
X412786Y-686561D01*
X412600Y-686436D01*
X411880D01*
Y-688936D01*
X412760D01*
X412946Y-688769D01*
X413053Y-688519D01*
X413106Y-688228D01*
X413053Y-687936D01*
X412893Y-687686D01*
X412706Y-687603D01*
X411880D01*
G01X415173Y-688936D02*
Y-687269D01*
G01Y-687561D02*
X415066Y-687394D01*
X414906Y-687311D01*
X414720Y-687269D01*
X414533Y-687353D01*
X414373Y-687519D01*
X414266Y-687769D01*
X414213Y-688103D01*
X414266Y-688436D01*
X414373Y-688686D01*
X414533Y-688853D01*
X414720Y-688936D01*
X414906Y-688894D01*
X415066Y-688769D01*
X415173Y-688603D01*
G01X416493Y-688644D02*
X416626Y-688811D01*
X416813Y-688936D01*
X416973D01*
X417133Y-688853D01*
X417240Y-688728D01*
X417293Y-688561D01*
X417266Y-688311D01*
X417160Y-688186D01*
X416680Y-687936D01*
X416573Y-687644D01*
X416626Y-687436D01*
X416733Y-687311D01*
X416893Y-687269D01*
X417053Y-687311D01*
X417213Y-687436D01*
G01X418693Y-687811D02*
X419546D01*
X419466Y-687519D01*
X419333Y-687353D01*
X419146Y-687269D01*
X418960Y-687311D01*
X418800Y-687436D01*
X418693Y-687728D01*
X418640Y-687978D01*
Y-688228D01*
X418693Y-688478D01*
X418826Y-688728D01*
X418986Y-688894D01*
X419173Y-688936D01*
X419360Y-688853D01*
X419546Y-688603D01*
G01X420813Y-688936D02*
Y-686436D01*
G01Y-687686D02*
X420946Y-687436D01*
X421106Y-687311D01*
X421266Y-687269D01*
X421506Y-687353D01*
X421666Y-687519D01*
X421773Y-687811D01*
Y-688144D01*
X421720Y-688478D01*
X421613Y-688728D01*
X421426Y-688894D01*
X421266Y-688936D01*
X421106Y-688894D01*
X420946Y-688769D01*
X420813Y-688561D01*
G01X423493Y-688936D02*
X423333Y-688894D01*
X423173Y-688728D01*
X423066Y-688436D01*
X423013Y-688103D01*
X423066Y-687769D01*
X423173Y-687478D01*
X423333Y-687311D01*
X423493Y-687269D01*
X423653Y-687311D01*
X423813Y-687478D01*
X423920Y-687769D01*
X423946Y-688103D01*
X423920Y-688436D01*
X423813Y-688728D01*
X423653Y-688894D01*
X423493Y-688936D01*
G01X426173D02*
Y-687269D01*
G01Y-687561D02*
X426066Y-687394D01*
X425906Y-687311D01*
X425720Y-687269D01*
X425533Y-687353D01*
X425373Y-687519D01*
X425266Y-687769D01*
X425213Y-688103D01*
X425266Y-688436D01*
X425373Y-688686D01*
X425533Y-688853D01*
X425720Y-688936D01*
X425906Y-688894D01*
X426066Y-688769D01*
X426173Y-688603D01*
G01X427520Y-688936D02*
Y-687269D01*
G01Y-687603D02*
X427653Y-687436D01*
X427786Y-687311D01*
X427973Y-687269D01*
X428106Y-687311D01*
X428266Y-687436D01*
G01X430573Y-686436D02*
Y-688936D01*
G01Y-688561D02*
X430466Y-688769D01*
X430306Y-688894D01*
X430120Y-688936D01*
X429906Y-688853D01*
X429746Y-688644D01*
X429640Y-688394D01*
X429613Y-688103D01*
X429640Y-687811D01*
X429746Y-687561D01*
X429906Y-687353D01*
X430120Y-687269D01*
X430306Y-687311D01*
X430440Y-687394D01*
X430573Y-687561D01*
G01X433960Y-688936D02*
Y-686436D01*
X434626D01*
X434840Y-686561D01*
X434973Y-686728D01*
X435026Y-687061D01*
X434973Y-687394D01*
X434813Y-687603D01*
X434626Y-687728D01*
X433960D01*
G01X434626D02*
X435026Y-688936D01*
G01X436293Y-687811D02*
X437146D01*
X437066Y-687519D01*
X436933Y-687353D01*
X436746Y-687269D01*
X436560Y-687311D01*
X436400Y-687436D01*
X436293Y-687728D01*
X436240Y-687978D01*
Y-688228D01*
X436293Y-688478D01*
X436426Y-688728D01*
X436586Y-688894D01*
X436773Y-688936D01*
X436960Y-688853D01*
X437146Y-688603D01*
G01X438413Y-687269D02*
X438893Y-688936D01*
X439373Y-687269D01*
G01X441093Y-689019D02*
X441040Y-688978D01*
Y-688894D01*
X441093Y-688853D01*
X441146Y-688894D01*
Y-688978D01*
X441093Y-689019D01*
G01X443613Y-688936D02*
Y-686436D01*
X442626Y-688228D01*
X443960D01*
G01X444826Y-688936D02*
X445493Y-686436D01*
X446160Y-688936D01*
G01X445920Y-688061D02*
X445066D01*
G01X408593Y-661936D02*
Y-666936D01*
G01X407136Y-661936D02*
X410050D01*
G01X413693Y-666936D02*
X413313Y-666853D01*
X412933Y-666519D01*
X412680Y-665936D01*
X412553Y-665269D01*
X412680Y-664603D01*
X412933Y-664019D01*
X413313Y-663686D01*
X413693Y-663603D01*
X414073Y-663686D01*
X414453Y-664019D01*
X414706Y-664603D01*
X414770Y-665269D01*
X414706Y-665936D01*
X414453Y-666519D01*
X414073Y-666853D01*
X413693Y-666936D01*
G01X418793D02*
X418413Y-666853D01*
X418033Y-666519D01*
X417780Y-665936D01*
X417653Y-665269D01*
X417780Y-664603D01*
X418033Y-664019D01*
X418413Y-663686D01*
X418793Y-663603D01*
X419173Y-663686D01*
X419553Y-664019D01*
X419806Y-664603D01*
X419870Y-665269D01*
X419806Y-665936D01*
X419553Y-666519D01*
X419173Y-666853D01*
X418793Y-666936D01*
G01X423893D02*
Y-661936D01*
G01X428993Y-667103D02*
X428866Y-667019D01*
Y-666853D01*
X428993Y-666769D01*
X429120Y-666853D01*
Y-667019D01*
X428993Y-667103D01*
G01Y-664853D02*
X428866Y-664769D01*
Y-664603D01*
X428993Y-664519D01*
X429120Y-664603D01*
Y-664769D01*
X428993Y-664853D01*
G01X407326Y-641936D02*
Y-636936D01*
X408910D01*
X409416Y-637186D01*
X409733Y-637519D01*
X409860Y-638186D01*
X409733Y-638853D01*
X409353Y-639269D01*
X408910Y-639519D01*
X407326D01*
G01X408910D02*
X409860Y-641936D01*
G01X414960D02*
X412426D01*
Y-636936D01*
X414960D01*
G01X413946Y-639353D02*
X412426D01*
G01X417210Y-636936D02*
X418793Y-641936D01*
X420376Y-636936D01*
G01X423893Y-642103D02*
X423766Y-642019D01*
Y-641853D01*
X423893Y-641769D01*
X424020Y-641853D01*
Y-642019D01*
X423893Y-642103D01*
G01Y-639853D02*
X423766Y-639769D01*
Y-639603D01*
X423893Y-639519D01*
X424020Y-639603D01*
Y-639769D01*
X423893Y-639853D01*
G01X2010999Y-388000D02*
Y1475775D01*
X-407000D01*
Y-386798D01*
Y-755294D01*
Y-793716D01*
X-368578D01*
X1942346D01*
X2010999D01*
Y-725063D01*
Y-388000D01*
G01X-42602Y-671096D02*
X-41975Y-671621D01*
X-41270Y-671936D01*
X-40644D01*
X-40017Y-671621D01*
X-39547Y-671096D01*
X-39312Y-670361D01*
X-39469Y-669626D01*
X-39860Y-668996D01*
X-40565Y-668576D01*
X-41505Y-668366D01*
X-42054Y-667946D01*
X-42289Y-667211D01*
X-42132Y-666476D01*
X-41740Y-665951D01*
X-41192Y-665636D01*
X-40644D01*
X-40095Y-665846D01*
X-39625Y-666371D01*
G01X-36302Y-671936D02*
Y-665636D01*
G01X-33012D02*
Y-671936D01*
G01Y-668786D02*
X-36302D01*
G01X-29297Y-665636D02*
X-27417D01*
G01X-28357D02*
Y-671936D01*
G01X-29297D02*
X-27417D01*
G01X-20490D02*
X-23624D01*
Y-665636D01*
X-20490D01*
G01X-21744Y-668681D02*
X-23624D01*
G01X-17559Y-671936D02*
Y-665636D01*
X-13955Y-671936D01*
Y-665636D01*
G01X-9614Y-673091D02*
X-9300Y-671726D01*
G01X-3157Y-665636D02*
Y-671936D01*
G01X-4959Y-665636D02*
X-1355D01*
G01X1185Y-671936D02*
X3143Y-665636D01*
X5101Y-671936D01*
G01X4396Y-669731D02*
X1890D01*
G01X8503Y-665636D02*
X10383D01*
G01X9443D02*
Y-671936D01*
G01X8503D02*
X10383D01*
G01X13393Y-665636D02*
X14490Y-671936D01*
X15743Y-665636D01*
X16996Y-671936D01*
X18093Y-665636D01*
G01X20085Y-671936D02*
X22043Y-665636D01*
X24001Y-671936D01*
G01X23296Y-669731D02*
X20790D01*
G01X26541Y-671936D02*
Y-665636D01*
X30145Y-671936D01*
Y-665636D01*
G01X39376Y-671936D02*
Y-665636D01*
X41335D01*
X41961Y-665951D01*
X42353Y-666371D01*
X42510Y-667211D01*
X42353Y-668051D01*
X41883Y-668576D01*
X41335Y-668891D01*
X39376D01*
G01X41335D02*
X42510Y-671936D01*
G01X47243Y-672146D02*
X47086Y-672041D01*
Y-671831D01*
X47243Y-671726D01*
X47400Y-671831D01*
Y-672041D01*
X47243Y-672146D01*
G01X53543Y-671936D02*
X52916Y-671831D01*
X52368Y-671411D01*
X51898Y-670781D01*
X51585Y-670046D01*
X51428Y-669206D01*
Y-668366D01*
X51585Y-667526D01*
X51898Y-666791D01*
X52368Y-666161D01*
X52916Y-665741D01*
X53543Y-665636D01*
X54170Y-665741D01*
X54718Y-666161D01*
X55188Y-666791D01*
X55501Y-667526D01*
X55658Y-668366D01*
Y-669206D01*
X55501Y-670046D01*
X55188Y-670781D01*
X54718Y-671411D01*
X54170Y-671831D01*
X53543Y-671936D01*
G01X59843Y-672146D02*
X59686Y-672041D01*
Y-671831D01*
X59843Y-671726D01*
X60000Y-671831D01*
Y-672041D01*
X59843Y-672146D01*
G01X67866Y-666161D02*
X67396Y-665846D01*
X66848Y-665636D01*
X66221D01*
X65516Y-665951D01*
X64968Y-666476D01*
X64576Y-667106D01*
X64263Y-668156D01*
X64185Y-669101D01*
X64341Y-670046D01*
X64576Y-670676D01*
X65046Y-671306D01*
X65595Y-671726D01*
X66143Y-671936D01*
X66691D01*
X67240Y-671726D01*
X67710Y-671411D01*
X68101Y-670991D01*
G01X72443Y-672146D02*
X72286Y-672041D01*
Y-671831D01*
X72443Y-671726D01*
X72600Y-671831D01*
Y-672041D01*
X72443Y-672146D01*
G01X-42680Y-661936D02*
Y-655636D01*
G01X-39704D02*
X-42680Y-659521D01*
G01X-39234Y-661936D02*
X-41349Y-657736D01*
G01X-36380Y-655636D02*
Y-660151D01*
X-36067Y-661096D01*
X-35440Y-661726D01*
X-34657Y-661936D01*
X-33874Y-661726D01*
X-33247Y-661096D01*
X-32934Y-660151D01*
Y-655636D01*
G01X-26790Y-661936D02*
X-29924D01*
Y-655636D01*
X-26790D01*
G01X-28044Y-658681D02*
X-29924D01*
G01X-22997Y-655636D02*
X-21117D01*
G01X-22057D02*
Y-661936D01*
G01X-22997D02*
X-21117D01*
G01X-11102Y-661096D02*
X-10475Y-661621D01*
X-9770Y-661936D01*
X-9144D01*
X-8517Y-661621D01*
X-8047Y-661096D01*
X-7812Y-660361D01*
X-7969Y-659626D01*
X-8360Y-658996D01*
X-9065Y-658576D01*
X-10005Y-658366D01*
X-10554Y-657946D01*
X-10789Y-657211D01*
X-10632Y-656476D01*
X-10240Y-655951D01*
X-9692Y-655636D01*
X-9144D01*
X-8595Y-655846D01*
X-8125Y-656371D01*
G01X-4802Y-661936D02*
Y-655636D01*
G01X-1512D02*
Y-661936D01*
G01Y-658786D02*
X-4802D01*
G01X1185Y-661936D02*
X3143Y-655636D01*
X5101Y-661936D01*
G01X4396Y-659731D02*
X1890D01*
G01X7641Y-661936D02*
Y-655636D01*
X11245Y-661936D01*
Y-655636D01*
G01X20398Y-661936D02*
Y-655636D01*
G01X23688D02*
Y-661936D01*
G01Y-658786D02*
X20398D01*
G01X26698Y-661096D02*
X27325Y-661621D01*
X28030Y-661936D01*
X28656D01*
X29283Y-661621D01*
X29753Y-661096D01*
X29988Y-660361D01*
X29831Y-659626D01*
X29440Y-658996D01*
X28735Y-658576D01*
X27795Y-658366D01*
X27246Y-657946D01*
X27011Y-657211D01*
X27168Y-656476D01*
X27560Y-655951D01*
X28108Y-655636D01*
X28656D01*
X29205Y-655846D01*
X29675Y-656371D01*
G01X33703Y-655636D02*
X35583D01*
G01X34643D02*
Y-661936D01*
G01X33703D02*
X35583D01*
G01X38985D02*
X40943Y-655636D01*
X42901Y-661936D01*
G01X42196Y-659731D02*
X39690D01*
G01X45441Y-661936D02*
Y-655636D01*
X49045Y-661936D01*
Y-655636D01*
G01X54013Y-658786D02*
X55580D01*
Y-660676D01*
X55110Y-661306D01*
X54561Y-661726D01*
X53778Y-661936D01*
X52995Y-661726D01*
X52446Y-661306D01*
X51976Y-660676D01*
X51663Y-659941D01*
X51506Y-659101D01*
Y-658366D01*
X51663Y-657736D01*
X51976Y-657001D01*
X52446Y-656371D01*
X52916Y-655951D01*
X53543Y-655636D01*
X54091D01*
X54718Y-655846D01*
X55188Y-656266D01*
G01X59686Y-663091D02*
X60000Y-661726D01*
G01X66143Y-655636D02*
Y-661936D01*
G01X64341Y-655636D02*
X67945D01*
G01X70485Y-661936D02*
X72443Y-655636D01*
X74401Y-661936D01*
G01X73696Y-659731D02*
X71190D01*
G01X78743Y-661936D02*
X78116Y-661831D01*
X77568Y-661411D01*
X77098Y-660781D01*
X76785Y-660046D01*
X76628Y-659206D01*
Y-658366D01*
X76785Y-657526D01*
X77098Y-656791D01*
X77568Y-656161D01*
X78116Y-655741D01*
X78743Y-655636D01*
X79370Y-655741D01*
X79918Y-656161D01*
X80388Y-656791D01*
X80701Y-657526D01*
X80858Y-658366D01*
Y-659206D01*
X80701Y-660046D01*
X80388Y-660781D01*
X79918Y-661411D01*
X79370Y-661831D01*
X78743Y-661936D01*
G01X91343D02*
Y-659101D01*
X89776Y-655636D01*
G01X92910D02*
X91343Y-659101D01*
G01X95920Y-655636D02*
Y-660151D01*
X96233Y-661096D01*
X96860Y-661726D01*
X97643Y-661936D01*
X98426Y-661726D01*
X99053Y-661096D01*
X99366Y-660151D01*
Y-655636D01*
G01X101985Y-661936D02*
X103943Y-655636D01*
X105901Y-661936D01*
G01X105196Y-659731D02*
X102690D01*
G01X108441Y-661936D02*
Y-655636D01*
X112045Y-661936D01*
Y-655636D01*
G01X-42759Y-651936D02*
Y-645636D01*
X-39155Y-651936D01*
Y-645636D01*
G01X-34657Y-651936D02*
X-35284Y-651831D01*
X-35832Y-651411D01*
X-36302Y-650781D01*
X-36615Y-650046D01*
X-36772Y-649206D01*
Y-648366D01*
X-36615Y-647526D01*
X-36302Y-646791D01*
X-35832Y-646161D01*
X-35284Y-645741D01*
X-34657Y-645636D01*
X-34030Y-645741D01*
X-33482Y-646161D01*
X-33012Y-646791D01*
X-32699Y-647526D01*
X-32542Y-648366D01*
Y-649206D01*
X-32699Y-650046D01*
X-33012Y-650781D01*
X-33482Y-651411D01*
X-34030Y-651831D01*
X-34657Y-651936D01*
G01X-28357Y-652146D02*
X-28514Y-652041D01*
Y-651831D01*
X-28357Y-651726D01*
X-28200Y-651831D01*
Y-652041D01*
X-28357Y-652146D01*
G01X-22057Y-651936D02*
Y-645636D01*
X-22997Y-646896D01*
G01Y-651936D02*
X-21117D01*
G01X-15757D02*
X-15209Y-651831D01*
X-14582Y-651516D01*
X-14190Y-650991D01*
X-14034Y-650256D01*
X-14190Y-649521D01*
X-14660Y-648891D01*
X-15365Y-648576D01*
X-16149D01*
X-16619Y-648366D01*
X-17010Y-647841D01*
X-17167Y-647106D01*
X-16932Y-646371D01*
X-16384Y-645846D01*
X-15757Y-645636D01*
X-15130Y-645846D01*
X-14582Y-646371D01*
X-14347Y-647106D01*
X-14504Y-647841D01*
X-14895Y-648366D01*
X-15365Y-648576D01*
X-16149D01*
X-16854Y-648891D01*
X-17324Y-649521D01*
X-17480Y-650256D01*
X-17324Y-650991D01*
X-16932Y-651516D01*
X-16305Y-651831D01*
X-15757Y-651936D01*
G01X-9457D02*
X-8909Y-651831D01*
X-8282Y-651516D01*
X-7890Y-650991D01*
X-7734Y-650256D01*
X-7890Y-649521D01*
X-8360Y-648891D01*
X-9065Y-648576D01*
X-9849D01*
X-10319Y-648366D01*
X-10710Y-647841D01*
X-10867Y-647106D01*
X-10632Y-646371D01*
X-10084Y-645846D01*
X-9457Y-645636D01*
X-8830Y-645846D01*
X-8282Y-646371D01*
X-8047Y-647106D01*
X-8204Y-647841D01*
X-8595Y-648366D01*
X-9065Y-648576D01*
X-9849D01*
X-10554Y-648891D01*
X-11024Y-649521D01*
X-11180Y-650256D01*
X-11024Y-650991D01*
X-10632Y-651516D01*
X-10005Y-651831D01*
X-9457Y-651936D01*
G01X-3314Y-653091D02*
X-3000Y-651726D01*
G01X793Y-645636D02*
X1890Y-651936D01*
X3143Y-645636D01*
X4396Y-651936D01*
X5493Y-645636D01*
G01X11010Y-651936D02*
X7876D01*
Y-645636D01*
X11010D01*
G01X9756Y-648681D02*
X7876D01*
G01X13941Y-651936D02*
Y-645636D01*
X17545Y-651936D01*
Y-645636D01*
G01X26698Y-651936D02*
Y-645636D01*
G01X29988D02*
Y-651936D01*
G01Y-648786D02*
X26698D01*
G01X32293Y-645636D02*
X33390Y-651936D01*
X34643Y-645636D01*
X35896Y-651936D01*
X36993Y-645636D01*
G01X38985Y-651936D02*
X40943Y-645636D01*
X42901Y-651936D01*
G01X42196Y-649731D02*
X39690D01*
G01X52055Y-646686D02*
X52525Y-646056D01*
X53073Y-645741D01*
X53700Y-645636D01*
X54483Y-645846D01*
X55031Y-646371D01*
X55188Y-647001D01*
X55110Y-647631D01*
X54796Y-648156D01*
X53230Y-649206D01*
X52525Y-649941D01*
X52055Y-650991D01*
X51898Y-651936D01*
X55188D01*
G01X58041D02*
Y-645636D01*
X61645Y-651936D01*
Y-645636D01*
G01X64420Y-651936D02*
Y-645636D01*
X65986D01*
X66613Y-645951D01*
X67083Y-646371D01*
X67475Y-647001D01*
X67788Y-647736D01*
X67866Y-648786D01*
X67788Y-649836D01*
X67475Y-650571D01*
X67083Y-651201D01*
X66613Y-651621D01*
X65986Y-651936D01*
X64420D01*
G01X77176D02*
Y-645636D01*
X79135D01*
X79761Y-645951D01*
X80153Y-646371D01*
X80310Y-647211D01*
X80153Y-648051D01*
X79683Y-648576D01*
X79135Y-648891D01*
X77176D01*
G01X79135D02*
X80310Y-651936D01*
G01X83320D02*
Y-645636D01*
X84886D01*
X85513Y-645951D01*
X85983Y-646371D01*
X86375Y-647001D01*
X86688Y-647736D01*
X86766Y-648786D01*
X86688Y-649836D01*
X86375Y-650571D01*
X85983Y-651201D01*
X85513Y-651621D01*
X84886Y-651936D01*
X83320D01*
G01X91343Y-652146D02*
X91186Y-652041D01*
Y-651831D01*
X91343Y-651726D01*
X91500Y-651831D01*
Y-652041D01*
X91343Y-652146D01*
G01X-18657Y-639236D02*
X-21177Y-638819D01*
X-23382Y-637153D01*
X-25272Y-634653D01*
X-26532Y-631736D01*
X-27162Y-628403D01*
Y-625069D01*
X-26532Y-621736D01*
X-25272Y-618819D01*
X-23382Y-616320D01*
X-21177Y-614653D01*
X-18657Y-614236D01*
X-16137Y-614653D01*
X-13932Y-616320D01*
X-12042Y-618819D01*
X-10782Y-621736D01*
X-10152Y-625069D01*
Y-628403D01*
X-10782Y-631736D01*
X-12042Y-634653D01*
X-13932Y-637153D01*
X-16137Y-638819D01*
X-18657Y-639236D01*
G01X-16137Y-632569D02*
X-12357Y-639236D01*
G01X1188Y-622570D02*
Y-634236D01*
X2448Y-637153D01*
X4338Y-638819D01*
X6543Y-639236D01*
X8748Y-638819D01*
X10638Y-637153D01*
X11898Y-634236D01*
G01Y-639236D02*
Y-622570D01*
G01X37413Y-639236D02*
Y-622570D01*
G01Y-625486D02*
X36153Y-623820D01*
X34263Y-622986D01*
X32058Y-622570D01*
X29853Y-623403D01*
X27963Y-625069D01*
X26703Y-627570D01*
X26073Y-630903D01*
X26703Y-634236D01*
X27963Y-636737D01*
X29853Y-638403D01*
X32058Y-639236D01*
X34263Y-638819D01*
X36153Y-637570D01*
X37413Y-635903D01*
G01X51588Y-639236D02*
Y-622570D01*
G01Y-626736D02*
X52848Y-624653D01*
X54738Y-622986D01*
X57258Y-622570D01*
X59463Y-622986D01*
X61353Y-624653D01*
X62298Y-627570D01*
Y-639236D01*
G01X82143Y-614236D02*
Y-639236D01*
G01X77733Y-622570D02*
X86553D01*
G01X113013Y-639236D02*
Y-622570D01*
G01Y-625486D02*
X111753Y-623820D01*
X109863Y-622986D01*
X107658Y-622570D01*
X105453Y-623403D01*
X103563Y-625069D01*
X102303Y-627570D01*
X101673Y-630903D01*
X102303Y-634236D01*
X103563Y-636737D01*
X105453Y-638403D01*
X107658Y-639236D01*
X109863Y-638819D01*
X111753Y-637570D01*
X113013Y-635903D01*
G01X152693Y-618936D02*
Y-626936D01*
X156693D01*
G01X164493D02*
Y-621603D01*
G01Y-622536D02*
X164093Y-622003D01*
X163493Y-621736D01*
X162793Y-621603D01*
X162093Y-621869D01*
X161493Y-622403D01*
X161093Y-623203D01*
X160893Y-624269D01*
X161093Y-625336D01*
X161493Y-626136D01*
X162093Y-626669D01*
X162793Y-626936D01*
X163493Y-626803D01*
X164093Y-626403D01*
X164493Y-625870D01*
G01X168593Y-629336D02*
X169193Y-629603D01*
X169993Y-629336D01*
X170493Y-628803D01*
X170893Y-628136D01*
X171493Y-626003D01*
X172793Y-621603D01*
G01X169593D02*
X171493Y-626003D01*
G01X177193Y-623336D02*
X180393D01*
X180093Y-622403D01*
X179593Y-621869D01*
X178893Y-621603D01*
X178193Y-621736D01*
X177593Y-622136D01*
X177193Y-623069D01*
X176993Y-623870D01*
Y-624669D01*
X177193Y-625469D01*
X177693Y-626269D01*
X178293Y-626803D01*
X178993Y-626936D01*
X179693Y-626669D01*
X180393Y-625870D01*
G01X185293Y-626936D02*
Y-621603D01*
G01Y-622669D02*
X185793Y-622136D01*
X186293Y-621736D01*
X186993Y-621603D01*
X187493Y-621736D01*
X188093Y-622136D01*
G01X173993Y-676936D02*
Y-668936D01*
G01X177793D02*
X173993Y-673870D01*
G01X178393Y-676936D02*
X175693Y-671603D01*
G01X185993Y-676936D02*
Y-671603D01*
G01Y-672536D02*
X185593Y-672003D01*
X184993Y-671736D01*
X184293Y-671603D01*
X183593Y-671869D01*
X182993Y-672403D01*
X182593Y-673203D01*
X182393Y-674269D01*
X182593Y-675336D01*
X182993Y-676136D01*
X183593Y-676669D01*
X184293Y-676936D01*
X184993Y-676803D01*
X185593Y-676403D01*
X185993Y-675870D01*
G01X192193Y-671603D02*
Y-676936D01*
G01Y-669469D02*
X191993Y-669336D01*
Y-669069D01*
X192193Y-668936D01*
X192393Y-669069D01*
Y-669336D01*
X192193Y-669469D01*
G01X181793Y-647936D02*
X183793D01*
Y-650336D01*
X183193Y-651136D01*
X182493Y-651669D01*
X181493Y-651936D01*
X180493Y-651669D01*
X179793Y-651136D01*
X179193Y-650336D01*
X178793Y-649403D01*
X178593Y-648336D01*
Y-647403D01*
X178793Y-646603D01*
X179193Y-645669D01*
X179793Y-644869D01*
X180393Y-644336D01*
X181193Y-643936D01*
X181893D01*
X182693Y-644203D01*
X183293Y-644736D01*
G01X186893Y-651936D02*
Y-643936D01*
X191493Y-651936D01*
Y-643936D01*
G01X194993Y-651936D02*
Y-643936D01*
X196993D01*
X197793Y-644336D01*
X198393Y-644869D01*
X198893Y-645669D01*
X199293Y-646603D01*
X199393Y-647936D01*
X199293Y-649269D01*
X198893Y-650203D01*
X198393Y-651003D01*
X197793Y-651536D01*
X196993Y-651936D01*
X194993D01*
G01X204293Y-620269D02*
X204893Y-619469D01*
X205593Y-619069D01*
X206393Y-618936D01*
X207393Y-619203D01*
X208093Y-619869D01*
X208293Y-620669D01*
X208193Y-621470D01*
X207793Y-622136D01*
X205793Y-623469D01*
X204893Y-624403D01*
X204293Y-625736D01*
X204093Y-626936D01*
X208293D01*
G01X279293Y-670269D02*
X279893Y-669469D01*
X280593Y-669069D01*
X281393Y-668936D01*
X282393Y-669203D01*
X283093Y-669869D01*
X283293Y-670669D01*
X283193Y-671470D01*
X282793Y-672136D01*
X280793Y-673469D01*
X279893Y-674403D01*
X279293Y-675736D01*
X279093Y-676936D01*
X283293D01*
G01X289193Y-668936D02*
X288393Y-669203D01*
X287793Y-669869D01*
X287393Y-670669D01*
X287093Y-671736D01*
X286993Y-672936D01*
X287093Y-674136D01*
X287393Y-675203D01*
X287793Y-676003D01*
X288393Y-676669D01*
X289193Y-676936D01*
X289993Y-676669D01*
X290593Y-676003D01*
X290993Y-675203D01*
X291293Y-674136D01*
X291393Y-672936D01*
X291293Y-671736D01*
X290993Y-670669D01*
X290593Y-669869D01*
X289993Y-669203D01*
X289193Y-668936D01*
G01X295293Y-670269D02*
X295893Y-669469D01*
X296593Y-669069D01*
X297393Y-668936D01*
X298393Y-669203D01*
X299093Y-669869D01*
X299293Y-670669D01*
X299193Y-671470D01*
X298793Y-672136D01*
X296793Y-673469D01*
X295893Y-674403D01*
X295293Y-675736D01*
X295093Y-676936D01*
X299293D01*
G01X303293Y-670269D02*
X303893Y-669469D01*
X304593Y-669069D01*
X305393Y-668936D01*
X306393Y-669203D01*
X307093Y-669869D01*
X307293Y-670669D01*
X307193Y-671470D01*
X306793Y-672136D01*
X304793Y-673469D01*
X303893Y-674403D01*
X303293Y-675736D01*
X303093Y-676936D01*
X307293D01*
G01X311393Y-677203D02*
X314993Y-668936D01*
G01X321193Y-676936D02*
Y-668936D01*
X319993Y-670536D01*
G01Y-676936D02*
X322393D01*
G01X327293Y-670269D02*
X327893Y-669469D01*
X328593Y-669069D01*
X329393Y-668936D01*
X330393Y-669203D01*
X331093Y-669869D01*
X331293Y-670669D01*
X331193Y-671470D01*
X330793Y-672136D01*
X328793Y-673469D01*
X327893Y-674403D01*
X327293Y-675736D01*
X327093Y-676936D01*
X331293D01*
G01X335393Y-677203D02*
X338993Y-668936D01*
G01X345193D02*
X344393Y-669203D01*
X343793Y-669869D01*
X343393Y-670669D01*
X343093Y-671736D01*
X342993Y-672936D01*
X343093Y-674136D01*
X343393Y-675203D01*
X343793Y-676003D01*
X344393Y-676669D01*
X345193Y-676936D01*
X345993Y-676669D01*
X346593Y-676003D01*
X346993Y-675203D01*
X347293Y-674136D01*
X347393Y-672936D01*
X347293Y-671736D01*
X346993Y-670669D01*
X346593Y-669869D01*
X345993Y-669203D01*
X345193Y-668936D01*
G01X351493Y-676003D02*
X352193Y-676669D01*
X352993Y-676936D01*
X353793Y-676669D01*
X354493Y-675870D01*
X354993Y-674669D01*
X355193Y-673469D01*
Y-672003D01*
X354993Y-670803D01*
X354493Y-669736D01*
X353893Y-669203D01*
X353193Y-668936D01*
X352393Y-669203D01*
X351793Y-669736D01*
X351393Y-670536D01*
X351193Y-671603D01*
X351393Y-672536D01*
X351893Y-673469D01*
X352493Y-674003D01*
X353193Y-674136D01*
X353993Y-673870D01*
X354593Y-673203D01*
X355193Y-672003D01*
G01X278993Y-651936D02*
Y-643936D01*
X280993D01*
X281793Y-644336D01*
X282393Y-644869D01*
X282893Y-645669D01*
X283293Y-646603D01*
X283393Y-647936D01*
X283293Y-649269D01*
X282893Y-650203D01*
X282393Y-651003D01*
X281793Y-651536D01*
X280993Y-651936D01*
X278993D01*
G01X286693D02*
X289193Y-643936D01*
X291693Y-651936D01*
G01X290793Y-649136D02*
X287593D01*
G01X297193Y-643936D02*
X296393Y-644203D01*
X295793Y-644869D01*
X295393Y-645669D01*
X295093Y-646736D01*
X294993Y-647936D01*
X295093Y-649136D01*
X295393Y-650203D01*
X295793Y-651003D01*
X296393Y-651669D01*
X297193Y-651936D01*
X297993Y-651669D01*
X298593Y-651003D01*
X298993Y-650203D01*
X299293Y-649136D01*
X299393Y-647936D01*
X299293Y-646736D01*
X298993Y-645669D01*
X298593Y-644869D01*
X297993Y-644203D01*
X297193Y-643936D01*
G01X303293Y-651936D02*
Y-643936D01*
X307093D01*
G01X305693Y-647803D02*
X303293D01*
G01X313193Y-643936D02*
X312393Y-644203D01*
X311793Y-644869D01*
X311393Y-645669D01*
X311093Y-646736D01*
X310993Y-647936D01*
X311093Y-649136D01*
X311393Y-650203D01*
X311793Y-651003D01*
X312393Y-651669D01*
X313193Y-651936D01*
X313993Y-651669D01*
X314593Y-651003D01*
X314993Y-650203D01*
X315293Y-649136D01*
X315393Y-647936D01*
X315293Y-646736D01*
X314993Y-645669D01*
X314593Y-644869D01*
X313993Y-644203D01*
X313193Y-643936D01*
G01X321193D02*
Y-651936D01*
G01X318893Y-643936D02*
X323493D01*
G01X326593Y-651936D02*
Y-643936D01*
X329193Y-650603D01*
X331793Y-643936D01*
Y-651936D01*
G01X334993D02*
Y-643936D01*
X336993D01*
X337793Y-644336D01*
X338393Y-644869D01*
X338893Y-645669D01*
X339293Y-646603D01*
X339393Y-647936D01*
X339293Y-649269D01*
X338893Y-650203D01*
X338393Y-651003D01*
X337793Y-651536D01*
X336993Y-651936D01*
X334993D01*
G01X347393Y-644603D02*
X346793Y-644203D01*
X346093Y-643936D01*
X345293D01*
X344393Y-644336D01*
X343693Y-645003D01*
X343193Y-645803D01*
X342793Y-647136D01*
X342693Y-648336D01*
X342893Y-649536D01*
X343193Y-650336D01*
X343793Y-651136D01*
X344493Y-651669D01*
X345193Y-651936D01*
X345893D01*
X346593Y-651669D01*
X347193Y-651269D01*
X347693Y-650736D01*
G01X350993Y-651936D02*
Y-643936D01*
X352993D01*
X353793Y-644336D01*
X354393Y-644869D01*
X354893Y-645669D01*
X355293Y-646603D01*
X355393Y-647936D01*
X355293Y-649269D01*
X354893Y-650203D01*
X354393Y-651003D01*
X353793Y-651536D01*
X352993Y-651936D01*
X350993D01*
G01X361193Y-643936D02*
X360393Y-644203D01*
X359793Y-644869D01*
X359393Y-645669D01*
X359093Y-646736D01*
X358993Y-647936D01*
X359093Y-649136D01*
X359393Y-650203D01*
X359793Y-651003D01*
X360393Y-651669D01*
X361193Y-651936D01*
X361993Y-651669D01*
X362593Y-651003D01*
X362993Y-650203D01*
X363293Y-649136D01*
X363393Y-647936D01*
X363293Y-646736D01*
X362993Y-645669D01*
X362593Y-644869D01*
X361993Y-644203D01*
X361193Y-643936D01*
G01X298418Y-624819D02*
Y-618519D01*
X301394D01*
G01X300298Y-621564D02*
X298418D01*
G01X306206Y-618519D02*
X305579Y-618729D01*
X305109Y-619254D01*
X304796Y-619884D01*
X304561Y-620724D01*
X304483Y-621669D01*
X304561Y-622614D01*
X304796Y-623454D01*
X305109Y-624084D01*
X305579Y-624609D01*
X306206Y-624819D01*
X306833Y-624609D01*
X307303Y-624084D01*
X307616Y-623454D01*
X307851Y-622614D01*
X307929Y-621669D01*
X307851Y-620724D01*
X307616Y-619884D01*
X307303Y-619254D01*
X306833Y-618729D01*
X306206Y-618519D01*
G01X312506D02*
Y-624819D01*
G01X310704Y-618519D02*
X314308D01*
G01X316456Y-626919D02*
X321156D01*
G01X323069Y-624819D02*
Y-618519D01*
X325106Y-623769D01*
X327143Y-618519D01*
Y-624819D01*
G01X332816D02*
Y-620619D01*
G01Y-621354D02*
X332503Y-620934D01*
X332033Y-620724D01*
X331484Y-620619D01*
X330936Y-620829D01*
X330466Y-621249D01*
X330153Y-621879D01*
X329996Y-622719D01*
X330153Y-623559D01*
X330466Y-624189D01*
X330936Y-624609D01*
X331484Y-624819D01*
X332033Y-624714D01*
X332503Y-624399D01*
X332816Y-623979D01*
G01X336374Y-624819D02*
Y-620619D01*
G01Y-621669D02*
X336688Y-621144D01*
X337158Y-620724D01*
X337784Y-620619D01*
X338333Y-620724D01*
X338803Y-621144D01*
X339038Y-621879D01*
Y-624819D01*
G01X345416D02*
Y-620619D01*
G01Y-621354D02*
X345103Y-620934D01*
X344633Y-620724D01*
X344084Y-620619D01*
X343536Y-620829D01*
X343066Y-621249D01*
X342753Y-621879D01*
X342596Y-622719D01*
X342753Y-623559D01*
X343066Y-624189D01*
X343536Y-624609D01*
X344084Y-624819D01*
X344633Y-624714D01*
X345103Y-624399D01*
X345416Y-623979D01*
G01X349209Y-626394D02*
X349758Y-626814D01*
X350384Y-626919D01*
X350933Y-626814D01*
X351403Y-626289D01*
X351716Y-625554D01*
Y-620619D01*
G01Y-621459D02*
X351403Y-621039D01*
X350933Y-620724D01*
X350384Y-620619D01*
X349758Y-620829D01*
X349366Y-621249D01*
X349053Y-621984D01*
X348896Y-622719D01*
X348974Y-623349D01*
X349288Y-624084D01*
X349758Y-624609D01*
X350384Y-624819D01*
X350854Y-624714D01*
X351403Y-624294D01*
X351716Y-623874D01*
G01X355431Y-621984D02*
X357938D01*
X357703Y-621249D01*
X357311Y-620829D01*
X356763Y-620619D01*
X356214Y-620724D01*
X355744Y-621039D01*
X355431Y-621774D01*
X355274Y-622404D01*
Y-623034D01*
X355431Y-623664D01*
X355823Y-624294D01*
X356293Y-624714D01*
X356841Y-624819D01*
X357389Y-624609D01*
X357938Y-623979D01*
G01X360556Y-624819D02*
Y-620619D01*
G01Y-621774D02*
X360791Y-621249D01*
X361183Y-620829D01*
X361731Y-620619D01*
X362279Y-620829D01*
X362671Y-621249D01*
X362906Y-621774D01*
Y-624819D01*
G01Y-621774D02*
X363141Y-621249D01*
X363533Y-620829D01*
X364081Y-620619D01*
X364629Y-620829D01*
X365021Y-621249D01*
X365256Y-621879D01*
Y-624819D01*
G01X368031Y-621984D02*
X370538D01*
X370303Y-621249D01*
X369911Y-620829D01*
X369363Y-620619D01*
X368814Y-620724D01*
X368344Y-621039D01*
X368031Y-621774D01*
X367874Y-622404D01*
Y-623034D01*
X368031Y-623664D01*
X368423Y-624294D01*
X368893Y-624714D01*
X369441Y-624819D01*
X369989Y-624609D01*
X370538Y-623979D01*
G01X374174Y-624819D02*
Y-620619D01*
G01Y-621669D02*
X374488Y-621144D01*
X374958Y-620724D01*
X375584Y-620619D01*
X376133Y-620724D01*
X376603Y-621144D01*
X376838Y-621879D01*
Y-624819D01*
G01X381806Y-618519D02*
Y-624819D01*
G01X380709Y-620619D02*
X382903D01*
G01X385756Y-626919D02*
X390456D01*
G01X395033Y-621459D02*
X395346Y-621144D01*
X395581Y-620619D01*
X395738Y-619884D01*
X395581Y-619254D01*
X395268Y-618834D01*
X394719Y-618519D01*
X392604D01*
Y-624819D01*
X395189D01*
X395738Y-624399D01*
X396051Y-623769D01*
X396208Y-623034D01*
X396051Y-622299D01*
X395581Y-621669D01*
X395033Y-621459D01*
X392604D01*
G01X398983Y-624819D02*
Y-618519D01*
X400549D01*
X401176Y-618834D01*
X401646Y-619254D01*
X402038Y-619884D01*
X402351Y-620619D01*
X402429Y-621669D01*
X402351Y-622719D01*
X402038Y-623454D01*
X401646Y-624084D01*
X401176Y-624504D01*
X400549Y-624819D01*
X398983D01*
G01X367693Y-679936D02*
Y-671936D01*
X366493Y-673536D01*
G01Y-679936D02*
X368893D01*
G01X373793Y-676603D02*
X374493Y-675669D01*
X375093Y-675136D01*
X375893Y-674869D01*
X376593Y-675136D01*
X377093Y-675669D01*
X377493Y-676469D01*
X377593Y-677403D01*
X377493Y-678203D01*
X377093Y-679003D01*
X376493Y-679669D01*
X375793Y-679936D01*
X374993Y-679669D01*
X374293Y-678870D01*
X373893Y-677669D01*
X373793Y-676336D01*
X373993Y-674603D01*
X374293Y-673669D01*
X374793Y-672736D01*
X375493Y-672069D01*
X376193Y-671936D01*
X376893Y-672203D01*
X377393Y-672869D01*
G01X383693Y-680203D02*
X383493Y-680069D01*
Y-679803D01*
X383693Y-679669D01*
X383893Y-679803D01*
Y-680069D01*
X383693Y-680203D01*
G01X389793Y-676603D02*
X390493Y-675669D01*
X391093Y-675136D01*
X391893Y-674869D01*
X392593Y-675136D01*
X393093Y-675669D01*
X393493Y-676469D01*
X393593Y-677403D01*
X393493Y-678203D01*
X393093Y-679003D01*
X392493Y-679669D01*
X391793Y-679936D01*
X390993Y-679669D01*
X390293Y-678870D01*
X389893Y-677669D01*
X389793Y-676336D01*
X389993Y-674603D01*
X390293Y-673669D01*
X390793Y-672736D01*
X391493Y-672069D01*
X392193Y-671936D01*
X392893Y-672203D01*
X393393Y-672869D01*
G01X412693Y-679936D02*
Y-671936D01*
X411493Y-673536D01*
G01Y-679936D02*
X413893D01*
G01X420493D02*
X420693Y-678203D01*
X420993Y-676736D01*
X421393Y-675403D01*
X421893Y-673936D01*
X422693Y-671936D01*
X418693D01*
G01X428693Y-680203D02*
X428493Y-680069D01*
Y-679803D01*
X428693Y-679669D01*
X428893Y-679803D01*
Y-680069D01*
X428693Y-680203D01*
G01X434793Y-673269D02*
X435393Y-672469D01*
X436093Y-672069D01*
X436893Y-671936D01*
X437893Y-672203D01*
X438593Y-672869D01*
X438793Y-673669D01*
X438693Y-674470D01*
X438293Y-675136D01*
X436293Y-676469D01*
X435393Y-677403D01*
X434793Y-678736D01*
X434593Y-679936D01*
X438793D01*
G01X432493Y-654936D02*
Y-646936D01*
X434493D01*
X435293Y-647336D01*
X435893Y-647869D01*
X436393Y-648669D01*
X436793Y-649603D01*
X436893Y-650936D01*
X436793Y-652269D01*
X436393Y-653203D01*
X435893Y-654003D01*
X435293Y-654536D01*
X434493Y-654936D01*
X432493D01*
M02*
